G04*
G04 #@! TF.GenerationSoftware,Altium Limited,Altium Designer,23.6.0 (18)*
G04*
G04 Layer_Physical_Order=6*
G04 Layer_Color=16711680*
%FSLAX44Y44*%
%MOMM*%
G71*
G04*
G04 #@! TF.SameCoordinates,0D6CC9A4-690D-4EF8-AA6E-9FB67146BD04*
G04*
G04*
G04 #@! TF.FilePolarity,Positive*
G04*
G01*
G75*
%ADD12C,0.5000*%
%ADD13C,0.2000*%
%ADD25R,0.6200X0.5700*%
%ADD31R,0.9500X1.0000*%
%ADD32R,1.0000X0.9500*%
%ADD33R,0.6200X0.6000*%
%ADD35R,0.6000X0.6200*%
%ADD68C,0.1020*%
%ADD69C,0.1016*%
%ADD70C,1.0000*%
%ADD71C,0.3810*%
%ADD72C,0.4000*%
%ADD74C,0.2540*%
%ADD76R,2.0200X2.0200*%
%ADD77C,2.0200*%
%ADD78C,2.0900*%
%ADD79C,5.3000*%
%ADD80C,0.6000*%
%ADD81C,0.1010*%
%ADD82R,1.5000X0.4500*%
%ADD83R,1.5500X0.6000*%
%ADD84R,0.8500X0.3000*%
%ADD85R,1.6000X1.6000*%
%ADD86R,1.1000X0.3000*%
%ADD87R,0.8000X1.0000*%
%ADD88R,0.6000X0.5500*%
%ADD89C,6.2000*%
%ADD90R,0.5500X0.6000*%
%ADD91C,0.1397*%
G36*
X486165Y502652D02*
X484350Y501259D01*
X482427Y498753D01*
X481218Y495834D01*
X480805Y492701D01*
X481218Y489568D01*
X482427Y486649D01*
X484350Y484142D01*
X486857Y482219D01*
X489776Y481010D01*
X492909Y480597D01*
X496041Y481010D01*
X498960Y482219D01*
X501467Y484142D01*
X502652Y485686D01*
X503922Y485255D01*
X503922Y22072D01*
X502652Y21641D01*
X501036Y23746D01*
X498529Y25670D01*
X495610Y26879D01*
X492478Y27291D01*
X489345Y26879D01*
X486426Y25670D01*
X483919Y23746D01*
X481996Y21240D01*
X480786Y18320D01*
X480374Y15188D01*
X480786Y12055D01*
X481996Y9136D01*
X483919Y6629D01*
X485588Y5348D01*
X485157Y4078D01*
X4919Y4078D01*
X4078Y5042D01*
X4078Y487769D01*
X5348Y488022D01*
X6354Y485593D01*
X8278Y483086D01*
X10785Y481162D01*
X13704Y479953D01*
X16836Y479541D01*
X19969Y479953D01*
X22888Y481162D01*
X25395Y483086D01*
X27318Y485593D01*
X28528Y488512D01*
X28940Y491645D01*
X28528Y494777D01*
X27318Y497696D01*
X25395Y500203D01*
X22888Y502127D01*
X21621Y502651D01*
X21874Y503921D01*
X159754Y503922D01*
X160185Y502651D01*
X159146Y501854D01*
X157661Y499920D01*
X157164Y498720D01*
X154682Y497692D01*
X152151Y496001D01*
X149999Y493849D01*
X148308Y491318D01*
X147144Y488507D01*
X146550Y485522D01*
Y482478D01*
X147144Y479493D01*
X148308Y476682D01*
X149999Y474151D01*
X152151Y471999D01*
X154682Y470308D01*
X157493Y469144D01*
X160478Y468550D01*
X163522D01*
X166507Y469144D01*
X169318Y470308D01*
X171849Y471999D01*
X174001Y474151D01*
X175692Y476682D01*
X176313Y478181D01*
X177687D01*
X178308Y476682D01*
X179999Y474151D01*
X182151Y471999D01*
X184682Y470308D01*
X187493Y469144D01*
X190478Y468550D01*
X191317D01*
X191551Y468169D01*
X194296Y464955D01*
X197510Y462210D01*
X201113Y460002D01*
X205018Y458384D01*
X209128Y457398D01*
X213134Y457082D01*
X213341Y457041D01*
X289925D01*
X290302Y457116D01*
X298136Y456676D01*
X306245Y455299D01*
X314148Y453022D01*
X321746Y449874D01*
X328945Y445896D01*
X335652Y441137D01*
X340844Y436497D01*
X341717Y435588D01*
X341717Y435588D01*
X371338Y405967D01*
X371425Y405909D01*
X375046Y402816D01*
X379195Y400274D01*
X383690Y398412D01*
X388080Y397358D01*
X387930Y396088D01*
X383750D01*
Y382088D01*
X386685D01*
Y370764D01*
X386685Y370764D01*
X386949Y369437D01*
Y364257D01*
X386789Y364096D01*
X386028Y362258D01*
Y360269D01*
X386789Y358432D01*
X388195Y357025D01*
X390033Y356264D01*
X392022D01*
X393860Y357025D01*
X395266Y358432D01*
X396028Y360269D01*
Y362258D01*
X395266Y364096D01*
X395106Y364257D01*
Y370500D01*
X394842Y371826D01*
Y382088D01*
X397250D01*
Y395612D01*
X397250Y396088D01*
X398191Y396882D01*
X410000D01*
X410106Y396903D01*
X411215Y396682D01*
X412244Y395994D01*
X412932Y394965D01*
X413153Y393856D01*
X413132Y393750D01*
Y327021D01*
X413183Y326763D01*
X412827Y323147D01*
X411697Y319421D01*
X409862Y315988D01*
X407556Y313179D01*
X407338Y313033D01*
X394805Y300500D01*
X387000D01*
Y282697D01*
X385780Y282316D01*
X382588Y284023D01*
X379123Y285074D01*
X375732Y285408D01*
X375536Y285447D01*
X375536Y285447D01*
X375532Y285448D01*
X375531Y285448D01*
X375522D01*
X375521Y285448D01*
X375518Y285447D01*
X375514Y285448D01*
X233382D01*
X233090Y285390D01*
X228314Y285766D01*
X223371Y286952D01*
X218675Y288898D01*
X214341Y291553D01*
X210698Y294665D01*
X210533Y294912D01*
X204972Y300472D01*
X204753Y300619D01*
X202374Y302572D01*
X199429Y304146D01*
X196235Y305115D01*
X193171Y305417D01*
X192912Y305468D01*
X184000D01*
Y307850D01*
X185012Y308472D01*
X188067D01*
Y307550D01*
X198267D01*
Y308472D01*
X201678D01*
Y307550D01*
X211878D01*
Y308472D01*
X213624D01*
Y305800D01*
X227624D01*
Y319300D01*
X213624D01*
Y319300D01*
X212418Y319456D01*
Y321644D01*
X213624Y321800D01*
X213688Y321800D01*
X215176D01*
X215625Y321711D01*
X231239D01*
X232450Y321692D01*
X234336Y319807D01*
Y317394D01*
X234491Y316614D01*
X234933Y315952D01*
X236327Y314558D01*
X236989Y314116D01*
X237769Y313961D01*
X254625D01*
X254625Y313961D01*
X255405Y314116D01*
X256067Y314558D01*
X256067Y314558D01*
X257317Y315808D01*
X257759Y316470D01*
X257914Y317250D01*
Y330805D01*
X259570Y332461D01*
X268875D01*
X269072Y332500D01*
X270500D01*
Y333332D01*
X270759Y333720D01*
X270914Y334500D01*
Y344650D01*
X270759Y345430D01*
X270500Y345818D01*
Y346500D01*
X269706D01*
X269655Y346534D01*
X268875Y346689D01*
X255887D01*
X254414Y347970D01*
Y357647D01*
X254414Y357648D01*
X254876Y358211D01*
X270664D01*
Y357275D01*
X283164D01*
Y357735D01*
X289414D01*
Y368275D01*
Y376214D01*
X288323D01*
X288485Y376242D01*
X288629Y376326D01*
X288757Y376465D01*
X288867Y376660D01*
X288960Y376911D01*
X289037Y377217D01*
X289096Y377579D01*
X289139Y377997D01*
X289167Y378815D01*
X283704D01*
Y379815D01*
X278914D01*
Y375775D01*
X276914D01*
Y374276D01*
X270663D01*
Y373775D01*
X270124D01*
Y371735D01*
X270664D01*
Y368335D01*
X256285D01*
X247309Y377310D01*
Y427250D01*
X247114Y428229D01*
X246560Y429060D01*
X242560Y433060D01*
X241729Y433614D01*
X240750Y433809D01*
X228000D01*
X227021Y433614D01*
X226190Y433060D01*
X221563Y428432D01*
X221008Y427602D01*
X220813Y426623D01*
Y419640D01*
X220540Y419527D01*
X219134Y418120D01*
X219021Y417847D01*
X202038D01*
X201059Y417652D01*
X200228Y417098D01*
X187468Y404337D01*
X186913Y403507D01*
X186718Y402528D01*
Y357181D01*
X160866Y331329D01*
X91869D01*
X87309Y335889D01*
Y373609D01*
X95330Y381630D01*
X112578D01*
Y379689D01*
X132658D01*
Y381901D01*
X138500D01*
X139479Y382096D01*
X140310Y382650D01*
X148060Y390400D01*
X148614Y391231D01*
X148809Y392210D01*
Y442000D01*
X148614Y442979D01*
X148060Y443810D01*
X121867Y470002D01*
Y470248D01*
X125180Y473561D01*
X127194Y472398D01*
X130361Y471550D01*
X133639D01*
X136805Y472398D01*
X139644Y474038D01*
X141962Y476356D01*
X143602Y479194D01*
X144450Y482361D01*
Y485639D01*
X143602Y488806D01*
X141962Y491645D01*
X139644Y493963D01*
X136805Y495602D01*
X133639Y496450D01*
X130361D01*
X127194Y495602D01*
X124355Y493963D01*
X122037Y491645D01*
X120398Y488806D01*
X119550Y485639D01*
Y482361D01*
X120398Y479194D01*
X121561Y477180D01*
X117828Y473447D01*
X117080Y473219D01*
X116184Y473436D01*
X112439Y477180D01*
X113602Y479194D01*
X114450Y482361D01*
Y485639D01*
X113602Y488806D01*
X111962Y491645D01*
X109644Y493963D01*
X106805Y495602D01*
X103639Y496450D01*
X100361D01*
X97194Y495602D01*
X94355Y493963D01*
X92037Y491645D01*
X90398Y488806D01*
X89550Y485639D01*
Y482361D01*
X90398Y479194D01*
X92037Y476356D01*
X94355Y474038D01*
X97194Y472398D01*
X100361Y471550D01*
X103639D01*
X106805Y472398D01*
X108820Y473561D01*
X112191Y470190D01*
Y468142D01*
X112386Y467163D01*
X112940Y466333D01*
X113015Y466258D01*
X112296Y465224D01*
X107668Y467582D01*
X102727Y469187D01*
X97597Y470000D01*
X92403D01*
X87272Y469187D01*
X82332Y467582D01*
X77704Y465224D01*
X75132Y463355D01*
X74000Y463932D01*
Y464245D01*
X73239Y466082D01*
X71832Y467489D01*
X69995Y468250D01*
X68005D01*
X66168Y467489D01*
X64761Y466082D01*
X64000Y464245D01*
Y463003D01*
X62730Y462663D01*
X61395Y464976D01*
X58976Y467395D01*
X56014Y469105D01*
X53000Y469912D01*
Y459000D01*
X63912D01*
X63863Y459186D01*
X64017Y459366D01*
X65749Y459430D01*
X66168Y459011D01*
X68005Y458250D01*
X68250D01*
X68827Y457118D01*
X66776Y454296D01*
X64418Y449668D01*
X62812Y444728D01*
X62000Y439597D01*
Y434403D01*
X62812Y429272D01*
X64418Y424332D01*
X66776Y419704D01*
X69829Y415502D01*
X73502Y411829D01*
X77704Y408776D01*
X82332Y406418D01*
X87272Y404813D01*
X92403Y404000D01*
X97597D01*
X102727Y404813D01*
X107668Y406418D01*
X112296Y408776D01*
X116498Y411829D01*
X120171Y415502D01*
X123224Y419704D01*
X125582Y424332D01*
X127187Y429272D01*
X128000Y434403D01*
Y439597D01*
X127187Y444728D01*
X125582Y449668D01*
X123224Y454296D01*
X124258Y455015D01*
X139941Y439332D01*
Y396020D01*
X137169Y393248D01*
X132118D01*
Y394939D01*
X113118D01*
Y392895D01*
X94086D01*
X93107Y392701D01*
X92277Y392146D01*
X78940Y378810D01*
X78386Y377979D01*
X78191Y377000D01*
Y332365D01*
X78386Y331385D01*
X78940Y330555D01*
X86845Y322650D01*
X87675Y322096D01*
X88655Y321901D01*
X163710D01*
X164689Y322096D01*
X165520Y322650D01*
X194722Y351853D01*
X195277Y352683D01*
X195472Y353662D01*
X195472Y353663D01*
Y393352D01*
X206031Y403912D01*
X225288D01*
X226267Y404107D01*
X227098Y404661D01*
X232560Y410123D01*
X233114Y410953D01*
X233309Y411933D01*
Y417627D01*
X233403Y417690D01*
X235392D01*
X235941Y416543D01*
Y371597D01*
X236136Y370617D01*
X236690Y369787D01*
X245233Y361245D01*
X244747Y360071D01*
X241509D01*
X240729Y359916D01*
X240068Y359474D01*
X240068Y359474D01*
X239928Y359334D01*
X239928Y359334D01*
X225467Y344873D01*
X215625D01*
X214845Y344718D01*
X214183Y344276D01*
X213741Y343614D01*
X213586Y342834D01*
Y327537D01*
X212418Y327290D01*
X212316Y327290D01*
X208778D01*
Y321750D01*
X206778D01*
Y319750D01*
X201138D01*
Y316628D01*
X198807D01*
Y319750D01*
X193167D01*
Y321750D01*
D01*
Y319750D01*
X187527D01*
Y316628D01*
X181000D01*
Y317550D01*
X161500D01*
Y307850D01*
X158500D01*
Y291850D01*
X161500D01*
Y282150D01*
X181000D01*
Y291850D01*
X184000D01*
Y294232D01*
X192912D01*
X193150Y294279D01*
X195176Y293876D01*
X196893Y292729D01*
X197027Y292528D01*
X201690Y287865D01*
X202588Y286967D01*
X202588Y286967D01*
X202588Y286967D01*
X202681Y286905D01*
X206880Y283223D01*
X211615Y280059D01*
X216722Y277540D01*
X222114Y275710D01*
X227699Y274599D01*
X233271Y274234D01*
X233382Y274212D01*
Y274212D01*
X233382Y274212D01*
X374368D01*
X375479Y273827D01*
X375514Y273812D01*
X376784Y274089D01*
X377408Y274007D01*
X378250Y273658D01*
Y266681D01*
X401014D01*
X401947Y266430D01*
X404053D01*
X406088Y266976D01*
X407912Y268029D01*
X409402Y269518D01*
X410455Y271343D01*
X411000Y273377D01*
Y275484D01*
X410455Y277518D01*
X409402Y279343D01*
X407912Y280832D01*
X406088Y281885D01*
X404053Y282430D01*
X402500D01*
Y292305D01*
X415283Y305088D01*
X415341Y305175D01*
X418434Y308796D01*
X420976Y312945D01*
X422838Y317440D01*
X422862Y317540D01*
X424132Y317390D01*
X424132Y207136D01*
X424134Y207125D01*
X424132Y207115D01*
X424179Y206876D01*
X423771Y204821D01*
X422603Y203074D01*
X422396Y202935D01*
X420805Y201344D01*
X410750D01*
Y210094D01*
X402945D01*
X388556Y224483D01*
X388469Y224541D01*
X384848Y227634D01*
X380699Y230176D01*
X376204Y232038D01*
X371473Y233174D01*
X366726Y233547D01*
X366623Y233568D01*
X184250D01*
Y235950D01*
X181250D01*
Y245650D01*
X161750D01*
Y235950D01*
X158750D01*
Y219950D01*
X161750D01*
Y210250D01*
X166929D01*
Y196700D01*
X166418D01*
Y188040D01*
X165877D01*
Y184500D01*
X171517D01*
X177157D01*
Y186937D01*
X178767D01*
Y184150D01*
X184407D01*
X190047D01*
Y186564D01*
X193650D01*
Y184205D01*
X207650D01*
Y197705D01*
X193650D01*
Y195741D01*
X189507D01*
Y196350D01*
X179307D01*
Y196113D01*
X176618D01*
Y196700D01*
X176106D01*
Y210250D01*
X181250D01*
Y219950D01*
X184250D01*
Y222332D01*
X366623D01*
X366880Y222383D01*
X370497Y222027D01*
X374223Y220897D01*
X377656Y219062D01*
X380465Y216756D01*
X380611Y216538D01*
X395250Y201899D01*
Y194094D01*
Y187077D01*
X395000Y186144D01*
Y184037D01*
X395545Y182003D01*
X396599Y180179D01*
X398088Y178689D01*
X399912Y177636D01*
X401947Y177091D01*
X404053D01*
X406088Y177636D01*
X407912Y178689D01*
X409402Y180179D01*
X410455Y182003D01*
X411000Y184037D01*
Y185844D01*
X429000D01*
Y193649D01*
X430341Y194990D01*
X430483Y195203D01*
X432456Y197606D01*
X434039Y200567D01*
X435013Y203781D01*
X435316Y206854D01*
X435367Y207111D01*
X435368Y207115D01*
X435366Y207125D01*
X435368Y207136D01*
X435368Y345786D01*
X436638Y345886D01*
X437202Y342326D01*
X438588Y338060D01*
X440625Y334063D01*
X443261Y330434D01*
X446433Y327261D01*
X450063Y324625D01*
X454060Y322588D01*
X458326Y321202D01*
X462757Y320500D01*
X467243D01*
X471674Y321202D01*
X475940Y322588D01*
X479937Y324625D01*
X483567Y327261D01*
X486739Y330434D01*
X489375Y334063D01*
X491412Y338060D01*
X492798Y342326D01*
X493500Y346757D01*
Y351243D01*
X492798Y355674D01*
X491412Y359940D01*
X489375Y363937D01*
X486739Y367566D01*
X483567Y370739D01*
X479937Y373375D01*
X475940Y375412D01*
X471674Y376798D01*
X467243Y377500D01*
X462757D01*
X458326Y376798D01*
X454060Y375412D01*
X450063Y373375D01*
X446433Y370739D01*
X443261Y367566D01*
X440625Y363937D01*
X438588Y359940D01*
X437202Y355674D01*
X436638Y352114D01*
X435368Y352214D01*
X435368Y397939D01*
X435332Y398119D01*
X434991Y401580D01*
X433929Y405080D01*
X432205Y408307D01*
X429884Y411134D01*
X427057Y413455D01*
X423830Y415179D01*
X420330Y416241D01*
X416869Y416582D01*
X416689Y416618D01*
X398797D01*
X398540Y416567D01*
X394923Y416923D01*
X391197Y418053D01*
X387764Y419888D01*
X384955Y422194D01*
X384809Y422412D01*
X354438Y452783D01*
X354393Y452813D01*
X348391Y458252D01*
X341843Y463109D01*
X334850Y467300D01*
X327480Y470786D01*
X319804Y473533D01*
X311896Y475514D01*
X303831Y476710D01*
X295741Y477108D01*
X295688Y477118D01*
X246926D01*
X246500Y477756D01*
Y479745D01*
X245739Y481582D01*
X244332Y482989D01*
X242495Y483750D01*
X240505D01*
X238668Y482989D01*
X237261Y481582D01*
X236500Y479745D01*
Y477756D01*
X236074Y477118D01*
X232963D01*
X232803Y477086D01*
X230789Y477351D01*
X228764Y478190D01*
X227025Y479525D01*
X225690Y481264D01*
X224851Y483289D01*
X224586Y485303D01*
X224618Y485463D01*
Y486000D01*
X224582Y486183D01*
X224242Y489629D01*
X223184Y493118D01*
X221465Y496333D01*
X219152Y499152D01*
X216333Y501465D01*
X214113Y502651D01*
X214432Y503922D01*
X485734Y503922D01*
X486165Y502652D01*
D02*
G37*
G36*
X207922Y493173D02*
X209713Y492432D01*
X211251Y491251D01*
X212432Y489713D01*
X213174Y487922D01*
X213409Y486135D01*
X213382Y486000D01*
Y485463D01*
X213409Y485326D01*
X213772Y481645D01*
X214885Y477975D01*
X216693Y474592D01*
X219127Y471627D01*
X221661Y469547D01*
X221207Y468277D01*
X213341D01*
X213150Y468239D01*
X210262Y468523D01*
X207302Y469421D01*
X204574Y470879D01*
X203193Y472013D01*
X203131Y473281D01*
X204001Y474151D01*
X205692Y476682D01*
X206856Y479493D01*
X207450Y482478D01*
Y485522D01*
X206856Y488507D01*
X205692Y491318D01*
X205061Y492262D01*
X205660Y493382D01*
X206000D01*
X206135Y493409D01*
X207922Y493173D01*
D02*
G37*
G36*
X252375Y357648D02*
Y347040D01*
X255125Y344650D01*
X268875D01*
Y334500D01*
X258725D01*
X255875Y331650D01*
Y317250D01*
X254625Y316000D01*
X237769D01*
X236375Y317394D01*
Y320651D01*
X233307Y323719D01*
X233244D01*
X231255Y323750D01*
X215625D01*
Y342834D01*
X226311D01*
X241370Y357892D01*
X241509Y358032D01*
X251991D01*
X252375Y357648D01*
D02*
G37*
%LPC*%
G36*
X73639Y496450D02*
X70361D01*
X67194Y495602D01*
X64356Y493963D01*
X62038Y491645D01*
X60399Y488806D01*
X59550Y485639D01*
Y482361D01*
X60399Y479194D01*
X62038Y476356D01*
X64356Y474038D01*
X67194Y472398D01*
X70361Y471550D01*
X73639D01*
X76806Y472398D01*
X79644Y474038D01*
X81962Y476356D01*
X83602Y479194D01*
X84450Y482361D01*
Y485639D01*
X83602Y488806D01*
X81962Y491645D01*
X79644Y493963D01*
X76806Y495602D01*
X73639Y496450D01*
D02*
G37*
G36*
X49000Y469912D02*
X45986Y469105D01*
X43024Y467395D01*
X40605Y464976D01*
X38895Y462014D01*
X38088Y459000D01*
X49000D01*
Y469912D01*
D02*
G37*
G36*
X140744Y468508D02*
X138755D01*
X136918Y467747D01*
X135511Y466340D01*
X134750Y464503D01*
Y462514D01*
X135511Y460676D01*
X136918Y459269D01*
X138755Y458508D01*
X140744D01*
X142582Y459269D01*
X143989Y460676D01*
X144750Y462514D01*
Y464503D01*
X143989Y466340D01*
X142582Y467747D01*
X140744Y468508D01*
D02*
G37*
G36*
X49000Y455000D02*
X38088D01*
X38895Y451986D01*
X40605Y449024D01*
X43024Y446605D01*
X45986Y444895D01*
X49000Y444088D01*
Y455000D01*
D02*
G37*
G36*
X63912D02*
X53000D01*
Y444088D01*
X56014Y444895D01*
X58976Y446605D01*
X61395Y449024D01*
X63105Y451986D01*
X63912Y455000D01*
D02*
G37*
G36*
X415597Y485000D02*
X410403D01*
X405272Y484187D01*
X400332Y482582D01*
X395704Y480224D01*
X391502Y477171D01*
X387829Y473498D01*
X384776Y469296D01*
X382418Y464668D01*
X380813Y459728D01*
X380000Y454597D01*
Y449403D01*
X380813Y444272D01*
X382418Y439332D01*
X384776Y434704D01*
X387829Y430502D01*
X391502Y426829D01*
X395704Y423776D01*
X400332Y421418D01*
X405272Y419813D01*
X410403Y419000D01*
X415597D01*
X420728Y419813D01*
X425668Y421418D01*
X430296Y423776D01*
X434498Y426829D01*
X438171Y430502D01*
X441224Y434704D01*
X443582Y439332D01*
X445187Y444272D01*
X445336Y445214D01*
X446544Y445606D01*
X447151Y444999D01*
X449682Y443308D01*
X452493Y442144D01*
X455478Y441550D01*
X458522D01*
X461507Y442144D01*
X464318Y443308D01*
X466849Y444999D01*
X469001Y447151D01*
X470692Y449682D01*
X471856Y452493D01*
X472450Y455478D01*
Y458522D01*
X471856Y461507D01*
X470692Y464318D01*
X469001Y466849D01*
X466849Y469001D01*
X464318Y470692D01*
X461507Y471856D01*
X458522Y472450D01*
X455478D01*
X452493Y471856D01*
X449682Y470692D01*
X447151Y469001D01*
X444999Y466849D01*
X444263Y465746D01*
X442995Y465821D01*
X441224Y469296D01*
X438171Y473498D01*
X434498Y477171D01*
X430296Y480224D01*
X425668Y482582D01*
X420728Y484187D01*
X415597Y485000D01*
D02*
G37*
G36*
X338790Y420040D02*
X333500D01*
Y414500D01*
X338790D01*
Y420040D01*
D02*
G37*
G36*
X329500D02*
X324210D01*
Y414500D01*
X329500D01*
Y420040D01*
D02*
G37*
G36*
X338790Y410500D02*
X333500D01*
Y404960D01*
X338790D01*
Y410500D01*
D02*
G37*
G36*
X329500D02*
X324210D01*
Y404960D01*
X329500D01*
Y410500D01*
D02*
G37*
G36*
X74658Y395479D02*
X66618D01*
Y392689D01*
X74658D01*
Y395479D01*
D02*
G37*
G36*
X62618D02*
X54578D01*
Y392689D01*
X62618D01*
Y395479D01*
D02*
G37*
G36*
X381790Y396628D02*
X376500D01*
Y391088D01*
X381790D01*
Y396628D01*
D02*
G37*
G36*
X372500D02*
X367210D01*
Y391088D01*
X372500D01*
Y396628D01*
D02*
G37*
G36*
X346264Y398919D02*
X344275D01*
X342437Y398158D01*
X341031Y396751D01*
X340269Y394914D01*
Y392924D01*
X341031Y391087D01*
X341254Y390863D01*
Y390469D01*
X339312Y388527D01*
X338881Y388127D01*
X338544Y387857D01*
X338390Y387750D01*
X337671D01*
X337627Y387759D01*
X337584Y387750D01*
X333750D01*
X332790Y388498D01*
Y388540D01*
X329500D01*
Y383000D01*
X327500D01*
Y381000D01*
X322210D01*
Y378834D01*
X312164D01*
Y379275D01*
X310177D01*
X310133Y379284D01*
X310090Y379275D01*
X299664D01*
Y378815D01*
X293414D01*
Y376449D01*
X293526Y376326D01*
X293671Y376242D01*
X293832Y376214D01*
X293414D01*
Y368275D01*
Y357735D01*
X299664D01*
Y357275D01*
X301612D01*
X302047Y356660D01*
X301390Y355390D01*
X298900D01*
Y349750D01*
Y344110D01*
X299578D01*
X300257Y342840D01*
X300253Y342834D01*
X285500D01*
Y346500D01*
X273500D01*
Y332500D01*
X285500D01*
Y336166D01*
X303000D01*
X304276Y336420D01*
X305357Y337142D01*
X308458Y340243D01*
X309180Y341324D01*
X309434Y342600D01*
Y344650D01*
X311100D01*
Y354850D01*
X309248D01*
Y357275D01*
X312164D01*
Y362717D01*
X313941D01*
Y345250D01*
X313941Y345250D01*
X314174Y344080D01*
X314837Y343087D01*
X316337Y341587D01*
X316337Y341587D01*
X317329Y340924D01*
X318500Y340691D01*
X321250D01*
Y329500D01*
X329210D01*
Y328960D01*
X332750D01*
Y334250D01*
X334750D01*
Y336250D01*
X340290D01*
Y338012D01*
X341560Y338538D01*
X343482Y336616D01*
X343482Y336616D01*
X344805Y335732D01*
X346366Y335422D01*
X351757D01*
X351918Y335261D01*
X353755Y334500D01*
X355745D01*
X357582Y335261D01*
X358989Y336668D01*
X359750Y338505D01*
Y340495D01*
X358989Y342332D01*
X357582Y343739D01*
X355745Y344500D01*
X353755D01*
X351918Y343739D01*
X351757Y343578D01*
X348055D01*
X345000Y346634D01*
X343677Y347518D01*
X342116Y347828D01*
X342116Y347828D01*
X340742D01*
X339750Y348500D01*
Y349486D01*
X339750D01*
Y358460D01*
X340040D01*
Y361750D01*
X334500D01*
Y365750D01*
X340040D01*
Y369040D01*
X341223Y369250D01*
X343250D01*
Y382084D01*
X343259Y382127D01*
X343250Y382171D01*
Y382890D01*
X343341Y383021D01*
X343920Y383705D01*
X346945Y386730D01*
X347668Y387812D01*
X347922Y389088D01*
Y389606D01*
X348102Y389680D01*
X349508Y391087D01*
X350269Y392924D01*
Y394914D01*
X349508Y396751D01*
X348102Y398158D01*
X346264Y398919D01*
D02*
G37*
G36*
X322250Y419500D02*
X308750D01*
Y405500D01*
X310787D01*
Y394654D01*
X310250Y393358D01*
Y391369D01*
X311011Y389531D01*
X312418Y388124D01*
X314256Y387363D01*
X316245D01*
X318082Y388124D01*
X319489Y389531D01*
X320250Y391369D01*
Y393358D01*
X319963Y394050D01*
Y405500D01*
X322250D01*
Y419500D01*
D02*
G37*
G36*
X325500Y388540D02*
X322210D01*
Y385000D01*
X325500D01*
Y388540D01*
D02*
G37*
G36*
X381790Y387088D02*
X376500D01*
Y381548D01*
X381790D01*
Y387088D01*
D02*
G37*
G36*
X372500D02*
X367210D01*
Y381548D01*
X372500D01*
Y387088D01*
D02*
G37*
G36*
X274914Y379815D02*
X270124D01*
Y377775D01*
X274914D01*
Y379815D01*
D02*
G37*
G36*
X18780Y402960D02*
X16791D01*
X14953Y402199D01*
X13547Y400792D01*
X12785Y398955D01*
Y396965D01*
X13547Y395128D01*
X14953Y393721D01*
X16791Y392960D01*
X18780D01*
X20618Y393721D01*
X20778Y393882D01*
X20805D01*
X21710Y393000D01*
Y389710D01*
X27250D01*
Y385710D01*
X21710D01*
Y382420D01*
Y379710D01*
X27250D01*
Y375710D01*
X21710D01*
Y372420D01*
X20702Y371788D01*
X20493D01*
X20332Y371949D01*
X18495Y372710D01*
X16505D01*
X14668Y371949D01*
X13261Y370542D01*
X12500Y368704D01*
Y366715D01*
X13261Y364878D01*
X14668Y363471D01*
X15148Y363272D01*
Y361898D01*
X14668Y361699D01*
X13261Y360292D01*
X12500Y358455D01*
Y356465D01*
X13261Y354628D01*
X14668Y353221D01*
X16505Y352460D01*
X18495D01*
X20332Y353221D01*
X20493Y353382D01*
X20702D01*
X21710Y352750D01*
Y349460D01*
X27250D01*
Y347460D01*
X29250D01*
Y342170D01*
X32790D01*
Y342710D01*
X40750D01*
Y352210D01*
X40750D01*
Y352710D01*
X40750D01*
Y354901D01*
X45250D01*
X46229Y355096D01*
X47060Y355650D01*
X49310Y357900D01*
X49864Y358731D01*
X50059Y359710D01*
Y366961D01*
X51728Y368630D01*
X55118D01*
Y366939D01*
X74118D01*
Y373439D01*
Y385899D01*
X74658D01*
Y388689D01*
X54578D01*
Y386748D01*
X48331D01*
X45560Y389520D01*
X44729Y390074D01*
X43750Y390269D01*
X40750D01*
Y392460D01*
X40750D01*
X40785Y393210D01*
X40785D01*
X40785Y393715D01*
Y402710D01*
X22285D01*
Y402038D01*
X20778D01*
X20618Y402199D01*
X18780Y402960D01*
D02*
G37*
G36*
X111425Y364018D02*
X107885D01*
Y360378D01*
X111425D01*
Y364018D01*
D02*
G37*
G36*
Y356378D02*
X107885D01*
Y352738D01*
X111425D01*
Y356378D01*
D02*
G37*
G36*
X294900Y355390D02*
X291360D01*
Y351750D01*
X294900D01*
Y355390D01*
D02*
G37*
G36*
Y347750D02*
X291360D01*
Y344110D01*
X294900D01*
Y347750D01*
D02*
G37*
G36*
X25250Y345460D02*
X21710D01*
Y342170D01*
X25250D01*
Y345460D01*
D02*
G37*
G36*
X132658Y375689D02*
X112578D01*
Y372899D01*
X113118D01*
Y366939D01*
X119566D01*
Y365039D01*
X118965Y364018D01*
X115424D01*
Y358378D01*
Y352738D01*
X118396D01*
X119101Y351524D01*
X118743Y350710D01*
X116500D01*
Y336710D01*
X128500D01*
Y350710D01*
X125559D01*
Y353278D01*
X127625D01*
Y363478D01*
X125683D01*
Y366939D01*
X132118D01*
Y372899D01*
X132658D01*
Y375689D01*
D02*
G37*
G36*
X96604Y358378D02*
X94615D01*
X92777Y357617D01*
X91371Y356210D01*
X90610Y354372D01*
Y352383D01*
X91371Y350546D01*
X92777Y349139D01*
X94615Y348378D01*
X94842D01*
X99394Y343826D01*
X99394Y343826D01*
X100717Y342942D01*
X101500Y342786D01*
Y336710D01*
X113500D01*
Y350710D01*
X105894D01*
X105500Y350788D01*
X105500Y350788D01*
X103967D01*
X100610Y354145D01*
Y354372D01*
X99848Y356210D01*
X98442Y357617D01*
X96604Y358378D01*
D02*
G37*
G36*
X340290Y332250D02*
X336750D01*
Y328960D01*
X340290D01*
Y332250D01*
D02*
G37*
G36*
X198807Y327290D02*
X195167D01*
Y323750D01*
X198807D01*
Y327290D01*
D02*
G37*
G36*
X204778D02*
X201138D01*
Y323750D01*
X204778D01*
Y327290D01*
D02*
G37*
G36*
X191167D02*
X187527D01*
Y323750D01*
X191167D01*
Y327290D01*
D02*
G37*
G36*
X127000Y317550D02*
X107500D01*
Y311089D01*
X106492Y310082D01*
X95393D01*
X95393Y310082D01*
X95376D01*
X94398Y309887D01*
X93570Y309334D01*
X87931Y303695D01*
X87378Y302867D01*
X87183Y301889D01*
Y279285D01*
X85975Y278077D01*
X79000D01*
Y280000D01*
X64000D01*
Y270540D01*
X63460D01*
Y268500D01*
X64000D01*
Y268000D01*
X71500D01*
X79001D01*
Y268500D01*
X79540D01*
Y269923D01*
X87032D01*
X87059Y269928D01*
X88292D01*
X89269Y270123D01*
X90098Y270677D01*
X94583Y275162D01*
X95137Y275991D01*
X95331Y276968D01*
Y299607D01*
X97683Y301958D01*
X106680D01*
X107500Y301138D01*
Y294850D01*
X127000D01*
Y304850D01*
X111012D01*
X110480Y305382D01*
Y306709D01*
X111321Y307550D01*
X127000D01*
Y317550D01*
D02*
G37*
G36*
X245239Y297311D02*
X243250D01*
X241412Y296550D01*
X240006Y295143D01*
X239245Y293305D01*
Y291316D01*
X240006Y289479D01*
X241412Y288072D01*
X243250Y287311D01*
X245239D01*
X247077Y288072D01*
X248483Y289479D01*
X249245Y291316D01*
Y293305D01*
X248483Y295143D01*
X247077Y296550D01*
X245239Y297311D01*
D02*
G37*
G36*
X127000Y292150D02*
X107500D01*
Y282150D01*
X127000D01*
Y292150D01*
D02*
G37*
G36*
X181540Y279990D02*
X173250D01*
Y276450D01*
X181540D01*
Y279990D01*
D02*
G37*
G36*
X169250D02*
X160960D01*
Y276450D01*
X169250D01*
Y279990D01*
D02*
G37*
G36*
X127000Y279450D02*
X107500D01*
Y269450D01*
X127000D01*
Y279450D01*
D02*
G37*
G36*
X181540Y272450D02*
X173250D01*
Y268910D01*
X181540D01*
Y272450D01*
D02*
G37*
G36*
X169250D02*
X160960D01*
Y268910D01*
X169250D01*
Y272450D01*
D02*
G37*
G36*
X459000Y266912D02*
Y256000D01*
X469912D01*
X469105Y259014D01*
X467395Y261976D01*
X464976Y264395D01*
X462014Y266105D01*
X459000Y266912D01*
D02*
G37*
G36*
X455000Y266912D02*
X451986Y266105D01*
X449024Y264395D01*
X446605Y261976D01*
X444895Y259014D01*
X444088Y256000D01*
X455000D01*
Y266912D01*
D02*
G37*
G36*
X181790Y258890D02*
X173500D01*
Y255350D01*
X181790D01*
Y258890D01*
D02*
G37*
G36*
X169500D02*
X161210D01*
Y255350D01*
X169500D01*
Y258890D01*
D02*
G37*
G36*
X79001Y265001D02*
X71500D01*
X64000D01*
Y264500D01*
X63460D01*
Y262460D01*
X64000D01*
Y255540D01*
X63460D01*
Y253500D01*
X64000D01*
Y252999D01*
X71500D01*
X79001D01*
Y253500D01*
X79540D01*
Y255540D01*
X79000D01*
Y262460D01*
X79540D01*
Y264500D01*
X79001D01*
Y265001D01*
D02*
G37*
G36*
X244495Y262561D02*
X242505D01*
X240668Y261800D01*
X239261Y260393D01*
X238500Y258556D01*
Y256566D01*
X239261Y254729D01*
X240668Y253322D01*
X242505Y252561D01*
X244495D01*
X246332Y253322D01*
X247739Y254729D01*
X248500Y256566D01*
Y258556D01*
X247739Y260393D01*
X246332Y261800D01*
X244495Y262561D01*
D02*
G37*
G36*
X127250Y258350D02*
X107750D01*
Y248350D01*
X127250D01*
Y258350D01*
D02*
G37*
G36*
X44000Y280000D02*
X29000D01*
Y273000D01*
Y263000D01*
Y250540D01*
X28460D01*
Y248500D01*
X28999D01*
Y247999D01*
X36500D01*
X44000D01*
Y248500D01*
X44540D01*
Y250540D01*
X44000D01*
Y263000D01*
Y273000D01*
Y280000D01*
D02*
G37*
G36*
X181790Y251350D02*
X173500D01*
Y247810D01*
X181790D01*
Y251350D01*
D02*
G37*
G36*
X169500D02*
X161210D01*
Y247810D01*
X169500D01*
Y251350D01*
D02*
G37*
G36*
X469912Y252000D02*
X459000D01*
Y241088D01*
X462014Y241895D01*
X464976Y243605D01*
X467395Y246024D01*
X469105Y248986D01*
X469912Y252000D01*
D02*
G37*
G36*
X455000D02*
X444088D01*
X444895Y248986D01*
X446605Y246024D01*
X449024Y243605D01*
X451986Y241895D01*
X455000Y241088D01*
Y252000D01*
D02*
G37*
G36*
X127250Y245650D02*
X107750D01*
Y235650D01*
X127250D01*
Y245650D01*
D02*
G37*
G36*
X79001Y250000D02*
X71500D01*
X64000D01*
Y249500D01*
X63460D01*
Y248077D01*
X55773D01*
X54795Y247882D01*
X53967Y247329D01*
X47654Y241016D01*
X47100Y240187D01*
X46906Y239210D01*
Y211295D01*
X47100Y210317D01*
X47654Y209489D01*
X53239Y203904D01*
X54068Y203350D01*
X55045Y203156D01*
X76442D01*
X77419Y203350D01*
X78248Y203904D01*
X82096Y207752D01*
X82650Y208581D01*
X82844Y209558D01*
Y217622D01*
X82918Y217696D01*
X93900D01*
Y211800D01*
X104100D01*
Y217284D01*
X107098D01*
X107750Y216632D01*
Y210250D01*
X127250D01*
Y220250D01*
X111356D01*
X109984Y221622D01*
X111312Y222950D01*
X127250D01*
Y232950D01*
X107750D01*
Y226612D01*
X106642Y225504D01*
X104100D01*
Y231100D01*
X93900D01*
Y225844D01*
X80601D01*
X79623Y225650D01*
X78795Y225096D01*
X75444Y221745D01*
X74890Y220917D01*
X74696Y219939D01*
Y211875D01*
X74125Y211304D01*
X57362D01*
X55054Y213612D01*
Y217250D01*
X55588Y217356D01*
X56845Y218195D01*
X57685Y219452D01*
X57979Y220935D01*
Y220935D01*
Y220935D01*
X57979D01*
X57685Y222418D01*
X56945Y223525D01*
X57685Y224632D01*
X57979Y226115D01*
Y226115D01*
Y226115D01*
X57979D01*
X57685Y227598D01*
X56845Y228855D01*
X56772Y228904D01*
X57379Y229813D01*
X57674Y231295D01*
Y231295D01*
Y231295D01*
X57674D01*
X57379Y232778D01*
X56539Y234035D01*
X55282Y234875D01*
X55054Y234920D01*
Y236893D01*
X58090Y239928D01*
X64000D01*
Y228000D01*
X79000D01*
Y238000D01*
Y247460D01*
X79540D01*
Y249500D01*
X79001D01*
Y250000D01*
D02*
G37*
G36*
X44000Y245000D02*
X36500D01*
X28999D01*
Y244500D01*
X28460D01*
Y242460D01*
X29000D01*
Y238000D01*
Y228000D01*
X44000D01*
Y233000D01*
Y242460D01*
X44540D01*
Y244500D01*
X44000D01*
Y245000D01*
D02*
G37*
G36*
X244933Y214744D02*
X242944D01*
X241106Y213983D01*
X239700Y212576D01*
X238939Y210738D01*
Y208749D01*
X239700Y206912D01*
X241106Y205505D01*
X241382Y205391D01*
Y204211D01*
X239006D01*
Y201748D01*
X237629D01*
Y203941D01*
X230800D01*
X230547Y205211D01*
X231256Y205505D01*
X232662Y206912D01*
X233424Y208749D01*
Y210738D01*
X232662Y212576D01*
X231256Y213983D01*
X229418Y214744D01*
X227429D01*
X225591Y213983D01*
X224185Y212576D01*
X223424Y210738D01*
Y209970D01*
X222245Y208792D01*
X221361Y207469D01*
X221051Y205908D01*
X221051Y205908D01*
Y203941D01*
X219129D01*
Y194441D01*
X220051D01*
Y191714D01*
X219890Y191553D01*
X219129Y189715D01*
Y187726D01*
X219890Y185889D01*
X221297Y184482D01*
X223134Y183721D01*
X225124D01*
X226961Y184482D01*
X228368Y185889D01*
X229129Y187726D01*
Y189715D01*
X228368Y191553D01*
X228207Y191714D01*
Y194441D01*
X237629D01*
Y196634D01*
X239006D01*
Y185711D01*
X239006D01*
X239415Y185099D01*
X238939Y183950D01*
Y181961D01*
X239700Y180123D01*
X241106Y178716D01*
X242944Y177955D01*
X244933D01*
X246771Y178716D01*
X248178Y180123D01*
X248939Y181961D01*
Y183950D01*
X248323Y185437D01*
X248505Y185711D01*
X248505D01*
Y194211D01*
Y204211D01*
X246496D01*
Y205391D01*
X246771Y205505D01*
X248178Y206912D01*
X248939Y208749D01*
Y210738D01*
X248178Y212576D01*
X246771Y213983D01*
X244933Y214744D01*
D02*
G37*
G36*
X315995Y208311D02*
X314006D01*
X312168Y207550D01*
X310761Y206143D01*
X310000Y204306D01*
Y202316D01*
X310761Y200479D01*
X312168Y199072D01*
X314006Y198311D01*
X315995D01*
X317832Y199072D01*
X319239Y200479D01*
X320000Y202316D01*
Y204306D01*
X319239Y206143D01*
X317832Y207550D01*
X315995Y208311D01*
D02*
G37*
G36*
X259933Y214744D02*
X257944D01*
X256106Y213983D01*
X254700Y212576D01*
X253939Y210738D01*
Y208749D01*
X254700Y206912D01*
X256106Y205505D01*
X256382Y205391D01*
Y203941D01*
X254006D01*
Y193941D01*
Y185441D01*
X254005D01*
X254410Y184837D01*
X253939Y183700D01*
Y181710D01*
X254700Y179873D01*
X256106Y178466D01*
X257944Y177705D01*
X259933D01*
X261771Y178466D01*
X263178Y179873D01*
X263939Y181710D01*
Y183700D01*
X263328Y185175D01*
X263505Y185441D01*
X263505D01*
Y196384D01*
X265505D01*
Y194191D01*
X273962D01*
X274712Y192921D01*
X274206Y191700D01*
Y189711D01*
X274967Y187873D01*
X276374Y186466D01*
X278212Y185705D01*
X280201D01*
X282038Y186466D01*
X283445Y187873D01*
X284206Y189711D01*
Y191700D01*
X283700Y192921D01*
X284006Y194191D01*
X284005D01*
Y203691D01*
X265505D01*
Y201498D01*
X263505D01*
Y203941D01*
X261496D01*
Y205391D01*
X261771Y205505D01*
X263178Y206912D01*
X263939Y208749D01*
Y210738D01*
X263178Y212576D01*
X261771Y213983D01*
X259933Y214744D01*
D02*
G37*
G36*
X57650Y191550D02*
X54771Y190779D01*
X51889Y189114D01*
X49535Y186761D01*
X47871Y183879D01*
X47620Y182941D01*
X46350Y183108D01*
Y191100D01*
X22150D01*
Y166900D01*
X46350D01*
Y174892D01*
X47620Y175059D01*
X47871Y174121D01*
X49535Y171239D01*
X51889Y168885D01*
X54771Y167221D01*
X57650Y166450D01*
Y179000D01*
Y191550D01*
D02*
G37*
G36*
X61650D02*
Y181000D01*
X72200D01*
X71429Y183879D01*
X69764Y186761D01*
X67411Y189114D01*
X64529Y190779D01*
X61650Y191550D01*
D02*
G37*
G36*
X177157Y180500D02*
X173517D01*
Y176960D01*
X177157D01*
Y180500D01*
D02*
G37*
G36*
X169517D02*
X165877D01*
Y176960D01*
X169517D01*
Y180500D01*
D02*
G37*
G36*
X190047Y180150D02*
X186407D01*
Y176610D01*
X190047D01*
Y180150D01*
D02*
G37*
G36*
X182407D02*
X178767D01*
Y176610D01*
X182407D01*
Y180150D01*
D02*
G37*
G36*
X207650Y181705D02*
X193650D01*
Y168205D01*
X207650D01*
Y170877D01*
X209007D01*
X209168Y170716D01*
X211005Y169955D01*
X212995D01*
X214832Y170716D01*
X216239Y172123D01*
X217000Y173960D01*
Y175950D01*
X216239Y177787D01*
X214832Y179194D01*
X212995Y179955D01*
X211005D01*
X209168Y179194D01*
X209007Y179033D01*
X207650D01*
Y181705D01*
D02*
G37*
G36*
X72200Y177000D02*
X61650D01*
Y166450D01*
X64529Y167221D01*
X67411Y168885D01*
X69764Y171239D01*
X71429Y174121D01*
X72200Y177000D01*
D02*
G37*
G36*
X352156Y131070D02*
X350167D01*
X348329Y130309D01*
X347171Y129150D01*
X346082Y130239D01*
X344245Y131000D01*
X342255D01*
X340418Y130239D01*
X339011Y128832D01*
X338250Y126995D01*
Y125005D01*
X339011Y123168D01*
X340418Y121761D01*
X340648Y121666D01*
Y120291D01*
X339918Y119989D01*
X338511Y118582D01*
X337750Y116745D01*
Y114755D01*
X338511Y112918D01*
X339918Y111511D01*
X340804Y111144D01*
Y109769D01*
X339738Y109328D01*
X338331Y107921D01*
X337570Y106083D01*
Y104094D01*
X338331Y102256D01*
X339738Y100850D01*
X339968Y100755D01*
Y99380D01*
X339238Y99078D01*
X337831Y97671D01*
X337070Y95833D01*
Y93844D01*
X337831Y92007D01*
X339238Y90600D01*
X340717Y89987D01*
X340844Y88669D01*
X340843Y88665D01*
X340418Y88489D01*
X339011Y87082D01*
X338250Y85245D01*
Y83255D01*
X339011Y81418D01*
X340418Y80011D01*
X340648Y79916D01*
Y78541D01*
X339918Y78239D01*
X338511Y76832D01*
X337750Y74995D01*
Y73005D01*
X338511Y71168D01*
X339918Y69761D01*
X340804Y69394D01*
Y68019D01*
X339738Y67578D01*
X338331Y66171D01*
X337570Y64333D01*
Y62344D01*
X338331Y60507D01*
X339738Y59100D01*
X339968Y59005D01*
Y57630D01*
X339238Y57328D01*
X337831Y55921D01*
X337070Y54083D01*
Y52094D01*
X337831Y50257D01*
X339238Y48850D01*
X339044Y47555D01*
X338750Y46845D01*
Y44856D01*
X339511Y43018D01*
X340918Y41611D01*
X341148Y41516D01*
Y40142D01*
X340418Y39839D01*
X339011Y38433D01*
X338250Y36595D01*
Y34606D01*
X339011Y32768D01*
X340418Y31361D01*
X342255Y30600D01*
X344245D01*
X346082Y31361D01*
X347489Y32768D01*
X348247Y34598D01*
X348917Y34320D01*
X350906D01*
X352743Y35081D01*
X354150Y36488D01*
X354245Y36718D01*
X355620D01*
X355922Y35988D01*
X357329Y34581D01*
X359167Y33820D01*
X361156D01*
X362994Y34581D01*
X364400Y35988D01*
X365161Y37826D01*
Y39815D01*
X364400Y41652D01*
X362994Y43059D01*
X361156Y43820D01*
X359167D01*
X357329Y43059D01*
X355922Y41652D01*
X355827Y41422D01*
X354452D01*
X354150Y42152D01*
X352743Y43559D01*
X350906Y44320D01*
X349903D01*
X348847Y44811D01*
X348750Y45493D01*
Y45897D01*
X349111Y46914D01*
X349923Y47070D01*
X351156D01*
X352994Y47831D01*
X354400Y49238D01*
X354495Y49468D01*
X355870D01*
X356172Y48738D01*
X357579Y47331D01*
X359417Y46570D01*
X361406D01*
X363243Y47331D01*
X364650Y48738D01*
X365411Y50575D01*
Y52565D01*
X364650Y54402D01*
X363243Y55809D01*
X361406Y56570D01*
X359417D01*
X357579Y55809D01*
X356172Y54402D01*
X356077Y54172D01*
X354702D01*
X354400Y54902D01*
X352994Y56309D01*
X351156Y57070D01*
X349167D01*
X347329Y56309D01*
X346836Y55816D01*
X346309Y55921D01*
X344902Y57328D01*
X344672Y57423D01*
Y58798D01*
X345402Y59100D01*
X346676Y60374D01*
X347775Y59275D01*
X349612Y58513D01*
X351601D01*
X353439Y59275D01*
X354846Y60681D01*
X354941Y60911D01*
X356316D01*
X356618Y60181D01*
X358025Y58775D01*
X359862Y58014D01*
X361851D01*
X363689Y58775D01*
X365096Y60181D01*
X365857Y62019D01*
Y64008D01*
X365096Y65846D01*
X363689Y67252D01*
X361851Y68014D01*
X359862D01*
X358025Y67252D01*
X356618Y65846D01*
X356523Y65616D01*
X355148D01*
X354846Y66346D01*
X353439Y67752D01*
X351601Y68513D01*
X349612D01*
X347775Y67752D01*
X346501Y66479D01*
X345402Y67578D01*
X344516Y67945D01*
Y69320D01*
X345582Y69761D01*
X346096Y70275D01*
X347329Y70831D01*
X348024Y70543D01*
X349167Y70070D01*
X351156D01*
X352994Y70831D01*
X354400Y72238D01*
X354495Y72468D01*
X355870D01*
X356172Y71738D01*
X357579Y70331D01*
X359417Y69570D01*
X361406D01*
X363243Y70331D01*
X364650Y71738D01*
X365411Y73576D01*
Y75565D01*
X364650Y77402D01*
X363243Y78809D01*
X361406Y79570D01*
X359417D01*
X357579Y78809D01*
X356172Y77402D01*
X356077Y77172D01*
X354702D01*
X354400Y77902D01*
X352994Y79309D01*
X351156Y80070D01*
X349167D01*
X347329Y79309D01*
X346816Y78796D01*
X346500Y78653D01*
X346311Y78731D01*
X346198Y79363D01*
X346216Y80145D01*
X347489Y81418D01*
X348250Y83255D01*
Y84636D01*
X349372Y85512D01*
X349423Y85524D01*
X349917Y85320D01*
X351906D01*
X353744Y86081D01*
X355150Y87488D01*
X355245Y87718D01*
X356620D01*
X356922Y86988D01*
X358329Y85581D01*
X360167Y84820D01*
X362156D01*
X363993Y85581D01*
X365400Y86988D01*
X366161Y88826D01*
Y90815D01*
X365400Y92652D01*
X363993Y94059D01*
X362156Y94820D01*
X360167D01*
X358329Y94059D01*
X356922Y92652D01*
X356827Y92422D01*
X355452D01*
X355150Y93152D01*
X353744Y94559D01*
X351906Y95320D01*
X349917D01*
X348340Y94667D01*
X347457Y95044D01*
X347070Y95346D01*
Y95833D01*
X346309Y97671D01*
X345030Y98950D01*
X345010Y99945D01*
X345060Y100346D01*
X345562Y100701D01*
X346871Y100362D01*
X346922Y100238D01*
X348329Y98831D01*
X350167Y98070D01*
X352156D01*
X353993Y98831D01*
X355400Y100238D01*
X355495Y100468D01*
X356870D01*
X357172Y99738D01*
X358579Y98331D01*
X360417Y97570D01*
X362406D01*
X364244Y98331D01*
X365650Y99738D01*
X366411Y101575D01*
Y103565D01*
X365650Y105402D01*
X364244Y106809D01*
X362406Y107570D01*
X360417D01*
X358579Y106809D01*
X357172Y105402D01*
X357077Y105172D01*
X355702D01*
X355400Y105902D01*
X353993Y107309D01*
X352156Y108070D01*
X350167D01*
X348421Y107347D01*
X348025Y107265D01*
X346996Y107469D01*
X346809Y107921D01*
X345402Y109328D01*
X344516Y109695D01*
Y111069D01*
X345582Y111511D01*
X346087Y112015D01*
X347332Y111768D01*
X347368Y111681D01*
X348775Y110275D01*
X350612Y109514D01*
X352601D01*
X354439Y110275D01*
X355846Y111681D01*
X355941Y111911D01*
X357316D01*
X357618Y111181D01*
X359025Y109775D01*
X360862Y109014D01*
X362851D01*
X364689Y109775D01*
X366096Y111181D01*
X366857Y113019D01*
Y115008D01*
X366096Y116846D01*
X364689Y118252D01*
X362851Y119014D01*
X360862D01*
X359025Y118252D01*
X357618Y116846D01*
X357523Y116616D01*
X356148D01*
X355846Y117346D01*
X354439Y118752D01*
X352601Y119514D01*
X350612D01*
X348775Y118752D01*
X348270Y118248D01*
X347025Y118496D01*
X346989Y118582D01*
X345582Y119989D01*
X345352Y120084D01*
Y121459D01*
X346082Y121761D01*
X347241Y122920D01*
X348329Y121831D01*
X350167Y121070D01*
X352156D01*
X353993Y121831D01*
X355400Y123238D01*
X355495Y123468D01*
X356870D01*
X357172Y122738D01*
X358579Y121331D01*
X360417Y120570D01*
X362406D01*
X364244Y121331D01*
X365650Y122738D01*
X366411Y124576D01*
Y126565D01*
X365650Y128402D01*
X364244Y129809D01*
X362406Y130570D01*
X360417D01*
X358579Y129809D01*
X357172Y128402D01*
X357077Y128172D01*
X355702D01*
X355400Y128902D01*
X353993Y130309D01*
X352156Y131070D01*
D02*
G37*
G36*
X467243Y166500D02*
X462757D01*
X458326Y165798D01*
X454060Y164412D01*
X450063Y162375D01*
X446433Y159739D01*
X443261Y156566D01*
X440625Y152937D01*
X438588Y148940D01*
X437202Y144674D01*
X436500Y140243D01*
Y135757D01*
X437202Y131326D01*
X438588Y127060D01*
X440625Y123063D01*
X443261Y119433D01*
X446433Y116261D01*
X450063Y113625D01*
X454060Y111588D01*
X458326Y110202D01*
X462757Y109500D01*
X467243D01*
X471674Y110202D01*
X475940Y111588D01*
X479937Y113625D01*
X483567Y116261D01*
X486739Y119433D01*
X489375Y123063D01*
X491412Y127060D01*
X492798Y131326D01*
X493500Y135757D01*
Y140243D01*
X492798Y144674D01*
X491412Y148940D01*
X489375Y152937D01*
X486739Y156566D01*
X483567Y159739D01*
X479937Y162375D01*
X475940Y164412D01*
X471674Y165798D01*
X467243Y166500D01*
D02*
G37*
G36*
X56084Y111500D02*
X54095D01*
X52257Y110739D01*
X50851Y109332D01*
X50090Y107495D01*
Y105505D01*
X50851Y103668D01*
X52257Y102261D01*
X54095Y101500D01*
X56084D01*
X57922Y102261D01*
X59328Y103668D01*
X60090Y105505D01*
Y107495D01*
X59328Y109332D01*
X57922Y110739D01*
X56084Y111500D01*
D02*
G37*
G36*
X92000Y124250D02*
X90011D01*
X88173Y123489D01*
X86767Y122082D01*
X86005Y120245D01*
Y118255D01*
X86767Y116418D01*
X88173Y115011D01*
X89254Y114563D01*
Y113189D01*
X88168Y112739D01*
X86761Y111332D01*
X86000Y109495D01*
Y107505D01*
X86761Y105668D01*
X87862Y104567D01*
X87577Y103236D01*
X87272Y103187D01*
X82332Y101582D01*
X77704Y99224D01*
X77505Y99079D01*
X76468Y99896D01*
X77036Y101267D01*
Y103256D01*
X76275Y105093D01*
X74868Y106500D01*
X73031Y107261D01*
X71041D01*
X69204Y106500D01*
X67797Y105093D01*
X67036Y103256D01*
Y101267D01*
X67797Y99429D01*
X69204Y98022D01*
X71041Y97261D01*
X72842D01*
X73370Y96476D01*
X73502Y96171D01*
X69829Y92498D01*
X66776Y88296D01*
X64418Y83668D01*
X62812Y78727D01*
X62000Y73597D01*
Y68403D01*
X62812Y63273D01*
X64418Y58332D01*
X66776Y53704D01*
X69829Y49502D01*
X73502Y45829D01*
X77704Y42776D01*
X82332Y40418D01*
X87272Y38813D01*
X92403Y38000D01*
X97597D01*
X102727Y38813D01*
X107668Y40418D01*
X112296Y42776D01*
X116498Y45829D01*
X120171Y49502D01*
X123224Y53704D01*
X125582Y58332D01*
X127187Y63273D01*
X128000Y68403D01*
Y73597D01*
X127187Y78727D01*
X125582Y83668D01*
X123224Y88296D01*
X120171Y92498D01*
X116498Y96171D01*
X114352Y97730D01*
X114765Y99000D01*
X115245D01*
X117082Y99761D01*
X118489Y101168D01*
X119250Y103005D01*
Y104995D01*
X118489Y106832D01*
X117082Y108239D01*
X115245Y109000D01*
X113255D01*
X111418Y108239D01*
X110011Y106832D01*
X109250Y104995D01*
Y103005D01*
X109672Y101986D01*
X108678Y101067D01*
X107668Y101582D01*
X102727Y103187D01*
X97597Y104000D01*
X95367D01*
X94841Y105270D01*
X95239Y105668D01*
X96000Y107505D01*
Y109495D01*
X95239Y111332D01*
X93832Y112739D01*
X92751Y113187D01*
Y114561D01*
X93838Y115011D01*
X95244Y116418D01*
X96005Y118255D01*
Y120245D01*
X95244Y122082D01*
X93838Y123489D01*
X92000Y124250D01*
D02*
G37*
G36*
X130495Y111500D02*
X128505D01*
X126668Y110739D01*
X125261Y109332D01*
X124500Y107495D01*
Y105505D01*
X125261Y103668D01*
X126668Y102261D01*
X128030Y101697D01*
X128040Y100327D01*
X126778Y99804D01*
X125371Y98397D01*
X124610Y96560D01*
Y94571D01*
X125371Y92733D01*
X126778Y91326D01*
X128615Y90565D01*
X130605D01*
X132442Y91326D01*
X133849Y92733D01*
X134610Y94571D01*
Y96560D01*
X133849Y98397D01*
X132442Y99804D01*
X131080Y100368D01*
X131070Y101738D01*
X132332Y102261D01*
X133739Y103668D01*
X134500Y105505D01*
Y107495D01*
X133739Y109332D01*
X132332Y110739D01*
X130495Y111500D01*
D02*
G37*
G36*
X56084Y98504D02*
X54095D01*
X52257Y97743D01*
X50851Y96336D01*
X50090Y94499D01*
Y92509D01*
X50851Y90672D01*
X52257Y89265D01*
X54095Y88504D01*
X56084D01*
X57922Y89265D01*
X59328Y90672D01*
X60090Y92509D01*
Y94499D01*
X59328Y96336D01*
X57922Y97743D01*
X56084Y98504D01*
D02*
G37*
G36*
X42910D02*
X40921D01*
X39083Y97743D01*
X37677Y96336D01*
X36916Y94499D01*
Y92509D01*
X37677Y90672D01*
X39083Y89265D01*
X40921Y88504D01*
X42910D01*
X44748Y89265D01*
X46154Y90672D01*
X46916Y92509D01*
Y94499D01*
X46154Y96336D01*
X44748Y97743D01*
X42910Y98504D01*
D02*
G37*
G36*
X28073D02*
X26083D01*
X24246Y97743D01*
X22839Y96336D01*
X22078Y94499D01*
Y92509D01*
X22839Y90672D01*
X24246Y89265D01*
X26083Y88504D01*
X28073D01*
X29910Y89265D01*
X31317Y90672D01*
X32078Y92509D01*
Y94499D01*
X31317Y96336D01*
X29910Y97743D01*
X28073Y98504D01*
D02*
G37*
G36*
X193900Y74250D02*
X191911D01*
X190073Y73489D01*
X188666Y72082D01*
X188616Y71960D01*
X187259Y72003D01*
X185971Y73291D01*
X184133Y74052D01*
X182144D01*
X180306Y73291D01*
X178900Y71885D01*
X178138Y70047D01*
Y68999D01*
X176868Y68473D01*
X176082Y69259D01*
X174245Y70020D01*
X172255D01*
X170418Y69259D01*
X169011Y67853D01*
X168250Y66015D01*
Y64026D01*
X169011Y62188D01*
X170418Y60782D01*
X172255Y60020D01*
X174245D01*
X176082Y60782D01*
X177489Y62188D01*
X178250Y64026D01*
Y65074D01*
X179520Y65600D01*
X180306Y64814D01*
X182144Y64052D01*
X184133D01*
X185971Y64814D01*
X187377Y66220D01*
X187428Y66342D01*
X188785Y66300D01*
X190073Y65011D01*
X191911Y64250D01*
X193900D01*
X195738Y65011D01*
X197144Y66418D01*
X197905Y68255D01*
Y70245D01*
X197144Y72082D01*
X195738Y73489D01*
X193900Y74250D01*
D02*
G37*
G36*
X162745Y69750D02*
X160755D01*
X158918Y68989D01*
X157511Y67582D01*
X156750Y65745D01*
Y63755D01*
X157511Y61918D01*
X158918Y60511D01*
X160755Y59750D01*
X162745D01*
X164582Y60511D01*
X165989Y61918D01*
X166750Y63755D01*
Y65745D01*
X165989Y67582D01*
X164582Y68989D01*
X162745Y69750D01*
D02*
G37*
G36*
X150495Y68250D02*
X148505D01*
X146668Y67489D01*
X145261Y66082D01*
X144500Y64245D01*
Y62255D01*
X145261Y60418D01*
X146668Y59011D01*
X148505Y58250D01*
X150495D01*
X152332Y59011D01*
X153739Y60418D01*
X154500Y62255D01*
Y64245D01*
X153739Y66082D01*
X152332Y67489D01*
X150495Y68250D01*
D02*
G37*
G36*
X458639Y63450D02*
X455361D01*
X452195Y62602D01*
X449356Y60963D01*
X447038Y58644D01*
X445398Y55806D01*
X444550Y52639D01*
Y49361D01*
X445398Y46195D01*
X447038Y43355D01*
X449356Y41038D01*
X452195Y39398D01*
X455361Y38550D01*
X458639D01*
X461805Y39398D01*
X464645Y41038D01*
X466963Y43355D01*
X468602Y46195D01*
X469450Y49361D01*
Y52639D01*
X468602Y55806D01*
X466963Y58644D01*
X464645Y60963D01*
X461805Y62602D01*
X458639Y63450D01*
D02*
G37*
G36*
X52639D02*
X49361D01*
X46195Y62602D01*
X43355Y60963D01*
X41038Y58644D01*
X39398Y55806D01*
X38550Y52639D01*
Y49361D01*
X39398Y46195D01*
X41038Y43355D01*
X43355Y41038D01*
X46195Y39398D01*
X49361Y38550D01*
X52639D01*
X55806Y39398D01*
X58644Y41038D01*
X60963Y43355D01*
X62602Y46195D01*
X63450Y49361D01*
Y52639D01*
X62602Y55806D01*
X60963Y58644D01*
X58644Y60963D01*
X55806Y62602D01*
X52639Y63450D01*
D02*
G37*
G36*
X308495Y131250D02*
X306505D01*
X304668Y130489D01*
X303261Y129082D01*
X302500Y127245D01*
Y125255D01*
X303261Y123418D01*
X304668Y122011D01*
X304898Y121916D01*
Y120541D01*
X304168Y120239D01*
X302761Y118832D01*
X302000Y116995D01*
Y115005D01*
X302761Y113168D01*
X304168Y111761D01*
X305054Y111394D01*
Y110019D01*
X303988Y109578D01*
X302581Y108171D01*
X301820Y106333D01*
Y104344D01*
X302581Y102507D01*
X303988Y101100D01*
X304218Y101005D01*
Y99630D01*
X303488Y99328D01*
X302081Y97921D01*
X301320Y96083D01*
Y94094D01*
X302081Y92256D01*
X303488Y90850D01*
X304967Y90237D01*
X305094Y88919D01*
X305093Y88915D01*
X304668Y88739D01*
X303261Y87332D01*
X302500Y85494D01*
Y83505D01*
X303261Y81668D01*
X304668Y80261D01*
X304898Y80166D01*
Y78791D01*
X304168Y78489D01*
X302761Y77082D01*
X302000Y75245D01*
Y73255D01*
X302761Y71418D01*
X304168Y70011D01*
X305054Y69644D01*
Y68269D01*
X303988Y67828D01*
X302581Y66421D01*
X301820Y64583D01*
Y62594D01*
X302581Y60757D01*
X303988Y59350D01*
X304218Y59255D01*
Y57880D01*
X303488Y57578D01*
X302081Y56171D01*
X301320Y54333D01*
Y52344D01*
X302081Y50507D01*
X303488Y49100D01*
X303294Y47806D01*
X303000Y47095D01*
Y45106D01*
X303761Y43268D01*
X305168Y41862D01*
X305398Y41766D01*
Y40392D01*
X304668Y40089D01*
X303261Y38682D01*
X302500Y36845D01*
Y34856D01*
X303261Y33018D01*
X304668Y31611D01*
X306505Y30850D01*
X308495D01*
X310332Y31611D01*
X311739Y33018D01*
X312500Y34856D01*
Y36845D01*
X311739Y38682D01*
X310332Y40089D01*
X310102Y40184D01*
Y41559D01*
X310832Y41862D01*
X312239Y43268D01*
X313000Y45106D01*
Y47095D01*
X312239Y48932D01*
X310832Y50339D01*
X311026Y51634D01*
X311320Y52344D01*
Y54333D01*
X310559Y56171D01*
X309152Y57578D01*
X308922Y57673D01*
Y59048D01*
X309652Y59350D01*
X311059Y60757D01*
X311820Y62594D01*
Y64583D01*
X311059Y66421D01*
X309652Y67828D01*
X308766Y68195D01*
Y69570D01*
X309832Y70011D01*
X311239Y71418D01*
X312000Y73255D01*
Y75245D01*
X311239Y77082D01*
X309832Y78489D01*
X309602Y78584D01*
Y79959D01*
X310332Y80261D01*
X311739Y81668D01*
X312500Y83505D01*
Y85494D01*
X311739Y87332D01*
X310332Y88739D01*
X308853Y89351D01*
X308726Y90670D01*
X308727Y90674D01*
X309152Y90850D01*
X310559Y92256D01*
X311320Y94094D01*
Y96083D01*
X310559Y97921D01*
X309152Y99328D01*
X308922Y99423D01*
Y100798D01*
X309652Y101100D01*
X311059Y102507D01*
X311820Y104344D01*
Y106333D01*
X311059Y108171D01*
X309652Y109578D01*
X308766Y109945D01*
Y111320D01*
X309832Y111761D01*
X311239Y113168D01*
X312000Y115005D01*
Y116995D01*
X311239Y118832D01*
X309832Y120239D01*
X309602Y120334D01*
Y121709D01*
X310332Y122011D01*
X311739Y123418D01*
X312500Y125255D01*
Y127245D01*
X311739Y129082D01*
X310332Y130489D01*
X308495Y131250D01*
D02*
G37*
G36*
X321245Y131000D02*
X319255D01*
X317418Y130239D01*
X316011Y128832D01*
X315250Y126995D01*
Y125005D01*
X316011Y123168D01*
X317418Y121761D01*
X317648Y121666D01*
Y120291D01*
X316918Y119989D01*
X315511Y118582D01*
X314750Y116745D01*
Y114755D01*
X315511Y112918D01*
X316918Y111511D01*
X317804Y111144D01*
Y109769D01*
X316738Y109328D01*
X315331Y107921D01*
X314570Y106083D01*
Y104094D01*
X315331Y102256D01*
X316738Y100850D01*
X316968Y100755D01*
Y99380D01*
X316238Y99078D01*
X314831Y97671D01*
X314070Y95833D01*
Y93844D01*
X314831Y92007D01*
X316238Y90600D01*
X317717Y89987D01*
X317844Y88669D01*
X317843Y88665D01*
X317418Y88489D01*
X316011Y87082D01*
X315250Y85245D01*
Y83255D01*
X316011Y81418D01*
X317418Y80011D01*
X317648Y79916D01*
Y78541D01*
X316918Y78239D01*
X315511Y76832D01*
X314750Y74995D01*
Y73005D01*
X315511Y71168D01*
X316918Y69761D01*
X317804Y69394D01*
Y68019D01*
X316738Y67578D01*
X315331Y66171D01*
X314570Y64333D01*
Y62344D01*
X315331Y60507D01*
X316738Y59100D01*
X316968Y59005D01*
Y57630D01*
X316238Y57328D01*
X314831Y55921D01*
X314070Y54083D01*
Y52094D01*
X314831Y50257D01*
X316238Y48850D01*
X316044Y47555D01*
X315750Y46845D01*
Y44856D01*
X316511Y43018D01*
X317918Y41611D01*
X318148Y41516D01*
Y40142D01*
X317418Y39839D01*
X316011Y38433D01*
X315250Y36595D01*
Y34606D01*
X316011Y32768D01*
X317418Y31361D01*
X319255Y30600D01*
X321245D01*
X323082Y31361D01*
X324489Y32768D01*
X325250Y34606D01*
Y36595D01*
X324489Y38433D01*
X323082Y39839D01*
X322852Y39934D01*
Y41309D01*
X323582Y41611D01*
X324989Y43018D01*
X325750Y44856D01*
Y46845D01*
X324989Y48683D01*
X323582Y50089D01*
X323776Y51384D01*
X324070Y52094D01*
Y54083D01*
X323309Y55921D01*
X321902Y57328D01*
X321672Y57423D01*
Y58798D01*
X322402Y59100D01*
X323809Y60507D01*
X324570Y62344D01*
Y64333D01*
X323809Y66171D01*
X322402Y67578D01*
X321516Y67945D01*
Y69320D01*
X322582Y69761D01*
X323989Y71168D01*
X324750Y73005D01*
Y74995D01*
X323989Y76832D01*
X322582Y78239D01*
X322352Y78334D01*
Y79709D01*
X323082Y80011D01*
X324489Y81418D01*
X325250Y83255D01*
Y85245D01*
X324489Y87082D01*
X323082Y88489D01*
X321603Y89101D01*
X321476Y90420D01*
X321477Y90424D01*
X321902Y90600D01*
X323309Y92007D01*
X324070Y93844D01*
Y95833D01*
X323309Y97671D01*
X321902Y99078D01*
X321672Y99173D01*
Y100548D01*
X322402Y100850D01*
X323809Y102256D01*
X324570Y104094D01*
Y106083D01*
X323809Y107921D01*
X322402Y109328D01*
X321516Y109695D01*
Y111069D01*
X322582Y111511D01*
X323989Y112918D01*
X324750Y114755D01*
Y116745D01*
X323989Y118582D01*
X322582Y119989D01*
X322352Y120084D01*
Y121459D01*
X323082Y121761D01*
X324489Y123168D01*
X325250Y125005D01*
Y126995D01*
X324489Y128832D01*
X323082Y130239D01*
X321245Y131000D01*
D02*
G37*
G36*
X332688Y130554D02*
X330699D01*
X328861Y129793D01*
X327455Y128387D01*
X326693Y126549D01*
Y124560D01*
X327455Y122722D01*
X328861Y121316D01*
X329091Y121220D01*
Y119846D01*
X328361Y119543D01*
X326955Y118137D01*
X326194Y116299D01*
Y114310D01*
X326955Y112472D01*
X328361Y111066D01*
X329248Y110698D01*
Y109324D01*
X328181Y108882D01*
X326775Y107476D01*
X326013Y105638D01*
Y103649D01*
X326775Y101811D01*
X328181Y100404D01*
X328411Y100309D01*
Y98934D01*
X327681Y98632D01*
X326275Y97226D01*
X325513Y95388D01*
Y93399D01*
X326275Y91561D01*
X327681Y90154D01*
X329160Y89542D01*
X329287Y88223D01*
X329287Y88219D01*
X328861Y88043D01*
X327455Y86637D01*
X326693Y84799D01*
Y82810D01*
X327455Y80972D01*
X328861Y79566D01*
X329091Y79470D01*
Y78096D01*
X328361Y77793D01*
X326955Y76387D01*
X326194Y74549D01*
Y72560D01*
X326955Y70722D01*
X328361Y69316D01*
X329248Y68948D01*
Y67574D01*
X328181Y67132D01*
X326775Y65725D01*
X326013Y63888D01*
Y61899D01*
X326775Y60061D01*
X328181Y58654D01*
X328411Y58559D01*
Y57184D01*
X327681Y56882D01*
X326275Y55476D01*
X325513Y53638D01*
Y51649D01*
X326275Y49811D01*
X327681Y48404D01*
X327488Y47110D01*
X327193Y46399D01*
Y44410D01*
X327955Y42572D01*
X329361Y41166D01*
X329591Y41070D01*
Y39696D01*
X328861Y39393D01*
X327455Y37987D01*
X326693Y36149D01*
Y34160D01*
X327455Y32322D01*
X328861Y30916D01*
X330699Y30155D01*
X332688D01*
X334526Y30916D01*
X335932Y32322D01*
X336693Y34160D01*
Y36149D01*
X335932Y37987D01*
X334526Y39393D01*
X334296Y39489D01*
Y40863D01*
X335026Y41166D01*
X336432Y42572D01*
X337193Y44410D01*
Y46399D01*
X336432Y48237D01*
X335026Y49643D01*
X335219Y50938D01*
X335513Y51649D01*
Y53638D01*
X334752Y55476D01*
X333346Y56882D01*
X333116Y56977D01*
Y58352D01*
X333846Y58654D01*
X335252Y60061D01*
X336013Y61899D01*
Y63888D01*
X335252Y65725D01*
X333846Y67132D01*
X332959Y67499D01*
Y68874D01*
X334026Y69316D01*
X335432Y70722D01*
X336194Y72560D01*
Y74549D01*
X335432Y76387D01*
X334026Y77793D01*
X333796Y77888D01*
Y79263D01*
X334526Y79566D01*
X335932Y80972D01*
X336693Y82810D01*
Y84799D01*
X335932Y86637D01*
X334526Y88043D01*
X333047Y88656D01*
X332920Y89974D01*
X332920Y89978D01*
X333346Y90154D01*
X334752Y91561D01*
X335513Y93399D01*
Y95388D01*
X334752Y97226D01*
X333346Y98632D01*
X333116Y98727D01*
Y100102D01*
X333846Y100404D01*
X335252Y101811D01*
X336013Y103649D01*
Y105638D01*
X335252Y107476D01*
X333846Y108882D01*
X332959Y109249D01*
Y110624D01*
X334026Y111066D01*
X335432Y112472D01*
X336194Y114310D01*
Y116299D01*
X335432Y118137D01*
X334026Y119543D01*
X333796Y119639D01*
Y121013D01*
X334526Y121316D01*
X335932Y122722D01*
X336693Y124560D01*
Y126549D01*
X335932Y128387D01*
X334526Y129793D01*
X332688Y130554D01*
D02*
G37*
G36*
X408597Y74000D02*
X403403D01*
X398273Y73187D01*
X393332Y71582D01*
X388704Y69224D01*
X384502Y66171D01*
X380829Y62498D01*
X377776Y58296D01*
X375418Y53668D01*
X373813Y48727D01*
X373000Y43597D01*
Y38403D01*
X373813Y33273D01*
X375418Y28332D01*
X377776Y23704D01*
X380829Y19502D01*
X384502Y15829D01*
X388704Y12776D01*
X393332Y10418D01*
X398273Y8813D01*
X403403Y8000D01*
X408597D01*
X413727Y8813D01*
X418668Y10418D01*
X423296Y12776D01*
X427498Y15829D01*
X431171Y19502D01*
X434224Y23704D01*
X436582Y28332D01*
X438187Y33273D01*
X439000Y38403D01*
Y43597D01*
X438187Y48727D01*
X436582Y53668D01*
X434224Y58296D01*
X431171Y62498D01*
X427498Y66171D01*
X423296Y69224D01*
X418668Y71582D01*
X413727Y73187D01*
X408597Y74000D01*
D02*
G37*
%LPD*%
G36*
X343016Y385719D02*
X342513Y385199D01*
X341722Y384265D01*
X341435Y383852D01*
X341219Y383475D01*
X341076Y383133D01*
X341004Y382828D01*
Y382559D01*
X341076Y382325D01*
X341219Y382127D01*
X337627Y385719D01*
X337825Y385576D01*
X338059Y385504D01*
X338328D01*
X338633Y385576D01*
X338974Y385719D01*
X339352Y385935D01*
X339765Y386222D01*
X340214Y386582D01*
X341219Y387516D01*
X343016Y385719D01*
D02*
G37*
G36*
X310153Y377156D02*
X310213Y377076D01*
X310313Y377005D01*
X310453Y376944D01*
X310633Y376893D01*
X310853Y376851D01*
X311113Y376818D01*
X311753Y376780D01*
X312133Y376775D01*
Y374775D01*
X311753Y374771D01*
X310853Y374700D01*
X310633Y374658D01*
X310453Y374606D01*
X310313Y374545D01*
X310213Y374475D01*
X310153Y374395D01*
X310133Y374306D01*
Y377245D01*
X310153Y377156D01*
D02*
G37*
G36*
X324811Y373775D02*
X324789Y373965D01*
X324727Y374135D01*
X324625Y374285D01*
X324482Y374415D01*
X324299Y374525D01*
X324076Y374615D01*
X323813Y374685D01*
X323509Y374735D01*
X323165Y374765D01*
X322780Y374775D01*
Y376775D01*
X323161Y376782D01*
X323801Y376838D01*
X324061Y376886D01*
X324281Y376949D01*
X324460Y377025D01*
X324600Y377116D01*
X324701Y377220D01*
X324761Y377338D01*
X324781Y377469D01*
X324811Y373775D01*
D02*
G37*
G36*
X330209Y376060D02*
X330270Y375890D01*
X330372Y375740D01*
X330514Y375610D01*
X330697Y375500D01*
X330920Y375410D01*
X331184Y375340D01*
X331488Y375290D01*
X331834Y375260D01*
X332220Y375250D01*
Y373250D01*
X331834Y373240D01*
X331488Y373210D01*
X331184Y373160D01*
X330920Y373090D01*
X330697Y373000D01*
X330514Y372890D01*
X330372Y372760D01*
X330270Y372610D01*
X330209Y372440D01*
X330189Y372250D01*
Y376250D01*
X330209Y376060D01*
D02*
G37*
G36*
X310153Y372156D02*
X310213Y372076D01*
X310313Y372005D01*
X310453Y371944D01*
X310633Y371893D01*
X310853Y371851D01*
X311113Y371818D01*
X311753Y371780D01*
X312133Y371775D01*
Y369775D01*
X311753Y369771D01*
X310853Y369700D01*
X310633Y369658D01*
X310453Y369606D01*
X310313Y369545D01*
X310213Y369475D01*
X310153Y369395D01*
X310133Y369306D01*
Y372245D01*
X310153Y372156D01*
D02*
G37*
G36*
X323441Y367488D02*
X324176Y366866D01*
X324501Y366639D01*
X324798Y366469D01*
X325067Y366356D01*
X325307Y366300D01*
X325519D01*
X325703Y366356D01*
X325859Y366469D01*
X323031Y363641D01*
X323144Y363797D01*
X323200Y363980D01*
Y364193D01*
X323144Y364433D01*
X323031Y364702D01*
X322861Y364999D01*
X322635Y365324D01*
X322352Y365678D01*
X321616Y366469D01*
X323031Y367884D01*
X323441Y367488D01*
D02*
G37*
G36*
X327810Y361041D02*
X327640Y360980D01*
X327490Y360878D01*
X327360Y360736D01*
X327250Y360553D01*
X327160Y360330D01*
X327090Y360066D01*
X327040Y359762D01*
X327010Y359416D01*
X327000Y359030D01*
X325000D01*
X324990Y359416D01*
X324960Y359762D01*
X324910Y360066D01*
X324840Y360330D01*
X324750Y360553D01*
X324640Y360736D01*
X324510Y360878D01*
X324360Y360980D01*
X324190Y361041D01*
X324000Y361061D01*
X328000D01*
X327810Y361041D01*
D02*
G37*
G36*
X327010Y358569D02*
X327040Y358224D01*
X327090Y357920D01*
X327160Y357656D01*
X327250Y357432D01*
X327360Y357250D01*
X327490Y357108D01*
X327640Y357006D01*
X327810Y356945D01*
X328000Y356925D01*
X324000D01*
X324190Y356945D01*
X324360Y357006D01*
X324510Y357108D01*
X324640Y357250D01*
X324750Y357432D01*
X324840Y357656D01*
X324910Y357920D01*
X324960Y358224D01*
X324990Y358569D01*
X325000Y358955D01*
X327000D01*
X327010Y358569D01*
D02*
G37*
G36*
X323311Y341750D02*
X323291Y341940D01*
X323230Y342110D01*
X323128Y342260D01*
X322986Y342390D01*
X322803Y342500D01*
X322580Y342590D01*
X322316Y342660D01*
X322011Y342710D01*
X321666Y342740D01*
X321281Y342750D01*
Y344750D01*
X321666Y344760D01*
X322011Y344790D01*
X322316Y344840D01*
X322580Y344910D01*
X322803Y345000D01*
X322986Y345110D01*
X323128Y345240D01*
X323230Y345390D01*
X323291Y345560D01*
X323311Y345750D01*
Y341750D01*
D02*
G37*
G36*
X328060Y341041D02*
X327890Y340980D01*
X327740Y340878D01*
X327610Y340736D01*
X327500Y340553D01*
X327410Y340330D01*
X327340Y340066D01*
X327290Y339762D01*
X327260Y339416D01*
X327250Y339030D01*
X325250D01*
X325240Y339416D01*
X325210Y339762D01*
X325160Y340066D01*
X325090Y340330D01*
X325000Y340553D01*
X324890Y340736D01*
X324760Y340878D01*
X324610Y340980D01*
X324440Y341041D01*
X324250Y341061D01*
X328250D01*
X328060Y341041D01*
D02*
G37*
G36*
X327260Y338584D02*
X327290Y338239D01*
X327340Y337934D01*
X327410Y337670D01*
X327500Y337447D01*
X327610Y337264D01*
X327740Y337122D01*
X327890Y337020D01*
X328060Y336959D01*
X328250Y336939D01*
X324250D01*
X324440Y336959D01*
X324610Y337020D01*
X324760Y337122D01*
X324890Y337264D01*
X325000Y337447D01*
X325090Y337670D01*
X325160Y337934D01*
X325210Y338239D01*
X325240Y338584D01*
X325250Y338970D01*
X327250D01*
X327260Y338584D01*
D02*
G37*
D12*
X184407Y191350D02*
X184605Y191152D01*
X200453D01*
X200650Y190955D01*
X171693Y191525D02*
X184232D01*
X171518Y191700D02*
X171693Y191525D01*
X184232D02*
X184407Y191350D01*
X171518Y191700D02*
Y215233D01*
X171500Y215250D02*
X171518Y215233D01*
X315375Y392488D02*
Y412375D01*
X315398Y412398D01*
X315250Y392363D02*
X315375Y392488D01*
D13*
X122618Y371189D02*
X122625Y371183D01*
Y358378D02*
Y371183D01*
X122500Y343710D02*
Y358253D01*
X122625Y358378D01*
X318500Y343750D02*
X326250D01*
X317000Y345250D02*
X318500Y343750D01*
X317000Y345250D02*
Y364250D01*
X315475Y365775D02*
X317000Y364250D01*
X305914Y365775D02*
X315475D01*
X326250Y334250D02*
Y343750D01*
X325750Y363750D02*
X326000D01*
X305914Y370775D02*
X318725D01*
X325750Y363750D01*
X326000Y354486D02*
X326250Y354236D01*
X326000Y354486D02*
Y363750D01*
X327500Y374500D02*
X327750Y374250D01*
X338500D01*
X326225Y375775D02*
X327500Y374500D01*
X305914Y375775D02*
X326225D01*
D25*
X99000Y226250D02*
D03*
Y216650D02*
D03*
D31*
X374500Y389088D02*
D03*
X390500D02*
D03*
X331500Y412500D02*
D03*
X315500D02*
D03*
D32*
X200650Y174955D02*
D03*
Y190955D02*
D03*
X220624Y328550D02*
D03*
Y312550D02*
D03*
D33*
X193167D02*
D03*
Y321750D02*
D03*
X206778D02*
D03*
Y312550D02*
D03*
X184407Y191350D02*
D03*
Y182150D02*
D03*
X171518Y182500D02*
D03*
Y191700D02*
D03*
D35*
X113425Y358378D02*
D03*
X122625D02*
D03*
X306100Y349750D02*
D03*
X296900D02*
D03*
D68*
X206560Y290939D02*
G03*
X233382Y279830I26821J26821D01*
G01*
X384620Y276061D02*
G03*
X375532Y279830I-9100J-9100D01*
G01*
X375521Y279830D02*
G03*
X375514Y279830I-7J-1020D01*
G01*
X429750Y397939D02*
G03*
X416689Y411000I-13061J0D01*
G01*
X426369Y198963D02*
G03*
X429750Y207115I-8155J8159D01*
G01*
D02*
G03*
X429750Y207136I-11536J8D01*
G01*
X411311Y309060D02*
G03*
X418750Y327021I-17960J17960D01*
G01*
X201000Y296500D02*
G03*
X192912Y299850I-8088J-8088D01*
G01*
X384584Y220511D02*
G03*
X366623Y227950I-17960J-17960D01*
G01*
X192000Y484000D02*
G03*
X213341Y462659I21341J0D01*
G01*
X219000Y485463D02*
G03*
X232963Y471500I13963J0D01*
G01*
X219000Y486000D02*
G03*
X206000Y499000I-13000J0D01*
G01*
X345690Y439561D02*
G03*
X289925Y462659I-55765J-55765D01*
G01*
X350465Y448811D02*
G03*
X295688Y471500I-54777J-54777D01*
G01*
X418750Y393750D02*
G03*
X410000Y402500I-8749J0D01*
G01*
X375311Y409939D02*
G03*
X393271Y402500I17960J17960D01*
G01*
X380836Y418439D02*
G03*
X398797Y411000I17960J17960D01*
G01*
X165750Y499000D02*
G03*
X162000Y495250I0J-3750D01*
G01*
X223373Y415288D02*
Y426623D01*
X228000Y431250D02*
X240750D01*
X223373Y426623D02*
X228000Y431250D01*
X244750Y376250D02*
Y427250D01*
X240750Y431250D02*
X244750Y427250D01*
X255225Y365775D02*
X276914D01*
X244750Y376250D02*
X255225Y365775D01*
X276908Y360770D02*
X276914Y360775D01*
X249327Y360770D02*
X276908D01*
X238500Y371597D02*
X249327Y360770D01*
X234398Y422690D02*
X238500Y418588D01*
Y371597D02*
Y418588D01*
X163710Y324460D02*
X192913Y353662D01*
X230750Y419042D02*
X234398Y422690D01*
X225288Y406471D02*
X230750Y411933D01*
Y419042D01*
X192913Y394412D02*
X204971Y406471D01*
X225288D01*
X192913Y353662D02*
Y394412D01*
X161926Y328770D02*
X189277Y356121D01*
X202038Y415288D02*
X223373D01*
X189277Y402528D02*
X202038Y415288D01*
X189277Y356121D02*
Y402528D01*
X375521Y279830D02*
X375532D01*
X233382Y279830D02*
X375514D01*
X429750Y207136D02*
X429750Y397939D01*
X421000Y193594D02*
X426369Y198963D01*
X394750Y292500D02*
X411311Y309060D01*
X418750Y327021D02*
Y393750D01*
X384620Y276061D02*
X386250Y274431D01*
X201000Y296500D02*
X206560Y290940D01*
X171250Y299850D02*
X192912D01*
X394750Y274431D02*
X403000D01*
X394750D02*
Y284000D01*
X384584Y220511D02*
X403000Y202094D01*
X171500Y227950D02*
X366623D01*
X403000Y193594D02*
X412500D01*
X403000Y185091D02*
Y193594D01*
X289925Y462659D02*
X289925D01*
X213341D02*
X289925D01*
X232963Y471500D02*
X295688D01*
X219000Y485463D02*
Y486000D01*
X398797Y411000D02*
X416689D01*
X393271Y402500D02*
X410000D01*
X345690Y439561D02*
X375311Y409939D01*
X350465Y448811D02*
X380836Y418439D01*
X165750Y499000D02*
X206000D01*
X162000Y484000D02*
Y495250D01*
X138500Y384460D02*
X146250Y392210D01*
Y442000D01*
X138229Y390689D02*
X142500Y394960D01*
Y440392D01*
X243939Y182955D02*
Y190528D01*
X258939Y182705D02*
Y190258D01*
X243755Y190711D02*
X243939Y190528D01*
X258755Y190441D02*
X258939Y190258D01*
X88655Y324460D02*
X163710D01*
X90809Y328770D02*
X161926D01*
X114750Y468142D02*
X142500Y440392D01*
X114750Y468142D02*
Y471250D01*
X119308Y468942D02*
Y471308D01*
Y468942D02*
X146250Y442000D01*
X122618Y384189D02*
X122889Y384460D01*
X94270Y384189D02*
X122618D01*
X122889Y384460D02*
X138500D01*
X84750Y374669D02*
X94270Y384189D01*
X47500Y359710D02*
Y368021D01*
X50668Y371189D01*
X64618D01*
X35750Y377710D02*
X35771Y377689D01*
X64618D01*
X47271Y384189D02*
X64618D01*
X43750Y387710D02*
X47271Y384189D01*
X122265Y390336D02*
X122618Y390689D01*
X94086Y390336D02*
X122265D01*
X80750Y377000D02*
X94086Y390336D01*
X80750Y332365D02*
Y377000D01*
X84750Y334829D02*
Y374669D01*
X122618Y390689D02*
X138229D01*
X80750Y332365D02*
X88655Y324460D01*
X84750Y334829D02*
X90809Y328770D01*
X35500Y387960D02*
Y397960D01*
Y387960D02*
X35750Y387710D01*
X43750D01*
X35750Y367710D02*
Y377710D01*
X45250Y357460D02*
X47500Y359710D01*
X35750Y357460D02*
X45250D01*
X35750Y347460D02*
Y357460D01*
X102000Y484000D02*
X114750Y471250D01*
X119308Y471308D02*
X132000Y484000D01*
D69*
X258939Y199125D02*
Y209744D01*
X243736Y199191D02*
X243939Y199394D01*
Y209744D01*
X258755Y198941D02*
X258939Y199125D01*
X232629Y199191D02*
X243736D01*
X258755Y198941D02*
X270505D01*
D70*
X16836Y491645D02*
D03*
X492909Y492701D02*
D03*
X492478Y15188D02*
D03*
D71*
X291078Y378999D02*
X296874Y384796D01*
X291078Y368611D02*
Y378999D01*
Y368611D02*
X291414Y368275D01*
D72*
X224379Y199191D02*
X225129Y199941D01*
X224129Y199191D02*
X224379D01*
X225129Y199941D02*
Y205908D01*
X228424Y209203D01*
Y209744D01*
X391028Y361264D02*
Y370500D01*
X390764Y370764D02*
X391028Y370500D01*
X390764Y370764D02*
Y388824D01*
X390500Y389088D02*
X390764Y388824D01*
X334750Y343750D02*
Y354236D01*
X346366Y339500D02*
X354750D01*
X342116Y343750D02*
X346366Y339500D01*
X334750Y343750D02*
X342116D01*
X224129Y188721D02*
Y199191D01*
X200650Y174955D02*
X212000D01*
X279005Y198941D02*
X279106Y198841D01*
Y190805D02*
X279206Y190705D01*
X279106Y190805D02*
Y198841D01*
X105500Y346710D02*
X107500Y344710D01*
X102277Y346710D02*
X105500D01*
X107500Y343710D02*
Y344710D01*
X95610Y353378D02*
X102277Y346710D01*
X206778Y312550D02*
X220624D01*
X193167D02*
X206778D01*
X171250D02*
X193167D01*
X17785Y397960D02*
X27285D01*
X17500Y367710D02*
X27250D01*
X17500Y357460D02*
X27250D01*
D74*
X206778Y321750D02*
G03*
X209711Y320535I2933J2933D01*
G01*
X193167Y321750D02*
X206778D01*
X209711Y320535D02*
X213750D01*
X171459Y173059D02*
Y182441D01*
X171400Y173000D02*
X171459Y173059D01*
Y182441D02*
X171518Y182500D01*
X184407Y173689D02*
Y182150D01*
X279500Y339500D02*
X303000D01*
X306100Y342600D01*
Y349750D01*
X305914Y349936D02*
X306100Y349750D01*
X305914Y349936D02*
Y360775D01*
X338500Y383000D02*
X344588Y389088D01*
Y393588D01*
X338500Y382750D02*
Y383000D01*
X344588Y393588D02*
X345250Y394250D01*
X264858Y375775D02*
X276914D01*
D76*
X34250Y179000D02*
D03*
D77*
X59650D02*
D03*
D78*
X192000Y484000D02*
D03*
X51000Y457000D02*
D03*
X457000Y51000D02*
D03*
Y457000D02*
D03*
X132000Y484000D02*
D03*
X102000D02*
D03*
X72000D02*
D03*
X457000Y254000D02*
D03*
X51000Y51000D02*
D03*
X162000Y484000D02*
D03*
D79*
X465000Y138000D02*
D03*
Y349000D02*
D03*
D80*
X315000Y203311D02*
D03*
X241500Y478750D02*
D03*
X220968Y339000D02*
D03*
X349911Y39320D02*
D03*
X350161Y52070D02*
D03*
X350607Y63513D02*
D03*
X350161Y75070D02*
D03*
X360411Y74570D02*
D03*
X360857Y63014D02*
D03*
X360411Y51570D02*
D03*
X360161Y38820D02*
D03*
X350911Y90320D02*
D03*
X351161Y103070D02*
D03*
X351607Y114514D02*
D03*
X351161Y126070D02*
D03*
X361411Y125570D02*
D03*
X361857Y114014D02*
D03*
X361411Y102570D02*
D03*
X361161Y89820D02*
D03*
X308000Y46100D02*
D03*
X320750Y45850D02*
D03*
X332193Y45405D02*
D03*
X343750Y45850D02*
D03*
X343250Y35600D02*
D03*
X331693Y35155D02*
D03*
X320250Y35600D02*
D03*
X307500Y35850D02*
D03*
Y84500D02*
D03*
X320250Y84250D02*
D03*
X331693Y83804D02*
D03*
X343250Y84250D02*
D03*
X342750Y74000D02*
D03*
X331194Y73554D02*
D03*
X319750Y74000D02*
D03*
X307000Y74250D02*
D03*
X306320Y53339D02*
D03*
X319070Y53089D02*
D03*
X330513Y52643D02*
D03*
X342070Y53089D02*
D03*
X342570Y63339D02*
D03*
X331013Y62893D02*
D03*
X319570Y63339D02*
D03*
X306820Y63589D02*
D03*
Y105339D02*
D03*
X319570Y105089D02*
D03*
X331013Y104643D02*
D03*
X342570Y105089D02*
D03*
X342070Y94839D02*
D03*
X330513Y94393D02*
D03*
X319070Y94839D02*
D03*
X306320Y95089D02*
D03*
X307000Y116000D02*
D03*
X319750Y115750D02*
D03*
X331194Y115304D02*
D03*
X342750Y115750D02*
D03*
X343250Y126000D02*
D03*
X331693Y125554D02*
D03*
X320250Y126000D02*
D03*
X307500Y126250D02*
D03*
X192905Y69250D02*
D03*
X183138Y69052D02*
D03*
X173250Y65020D02*
D03*
X161750Y64750D02*
D03*
X149500Y63250D02*
D03*
X234398Y422690D02*
D03*
X223373Y415288D02*
D03*
X298715Y489190D02*
D03*
X351500Y488750D02*
D03*
X445113Y472750D02*
D03*
X475000Y447750D02*
D03*
X331500Y400274D02*
D03*
X327000Y392924D02*
D03*
X342703Y406495D02*
D03*
X206542Y332843D02*
D03*
X193292Y330805D02*
D03*
X145000Y264000D02*
D03*
X156752Y276869D02*
D03*
X83952Y262552D02*
D03*
X17462Y347587D02*
D03*
X363500Y449682D02*
D03*
X241197Y308750D02*
D03*
X285250Y446030D02*
D03*
X372500Y440000D02*
D03*
X440352Y374949D02*
D03*
X294500Y454750D02*
D03*
X270921Y437500D02*
D03*
X267761Y319250D02*
D03*
X172000Y147750D02*
D03*
X158750Y132850D02*
D03*
X52118Y197290D02*
D03*
X65473Y198873D02*
D03*
X65619Y215500D02*
D03*
X66659Y224000D02*
D03*
X87000Y475250D02*
D03*
X117080Y493963D02*
D03*
X177000Y492750D02*
D03*
X209500Y489750D02*
D03*
X444999Y421418D02*
D03*
X69000Y463250D02*
D03*
X289250Y269500D02*
D03*
X343677Y360775D02*
D03*
X391028Y361264D02*
D03*
X354750Y339500D02*
D03*
X363284Y389088D02*
D03*
X259492Y353693D02*
D03*
X274414Y352344D02*
D03*
X334750Y326000D02*
D03*
X297250Y385500D02*
D03*
X228424Y209744D02*
D03*
X224129Y188721D02*
D03*
X243500Y244381D02*
D03*
X212000Y174955D02*
D03*
X159750Y177787D02*
D03*
X171400Y173000D02*
D03*
X258939Y182705D02*
D03*
X243939Y182955D02*
D03*
X270189Y187644D02*
D03*
X258939Y209744D02*
D03*
X243939D02*
D03*
X279206Y190705D02*
D03*
X315250Y392363D02*
D03*
X345269Y393919D02*
D03*
X169161Y102103D02*
D03*
X183138D02*
D03*
X172498Y113250D02*
D03*
X95610Y353378D02*
D03*
X184407Y173689D02*
D03*
X146750Y230310D02*
D03*
X350250Y211521D02*
D03*
X344750Y243000D02*
D03*
X332000D02*
D03*
X243500Y257561D02*
D03*
X293674Y244381D02*
D03*
X206956Y397805D02*
D03*
X207706Y432800D02*
D03*
X175750D02*
D03*
X51500Y390689D02*
D03*
X103750Y358378D02*
D03*
X142000Y359750D02*
D03*
X109250Y377668D02*
D03*
X139750Y463508D02*
D03*
X17785Y397960D02*
D03*
X17500Y388019D02*
D03*
Y377710D02*
D03*
Y367710D02*
D03*
Y357460D02*
D03*
X8744Y354901D02*
D03*
X244245Y292311D02*
D03*
X393250Y242500D02*
D03*
X272892Y294750D02*
D03*
X55967Y354628D02*
D03*
X27078Y93504D02*
D03*
X129610Y95565D02*
D03*
X55090Y93504D02*
D03*
X91000Y108500D02*
D03*
X391579Y185091D02*
D03*
X403000Y173750D02*
D03*
Y263500D02*
D03*
X414482Y274431D02*
D03*
X273500Y244381D02*
D03*
X258000D02*
D03*
Y292250D02*
D03*
X363962Y297432D02*
D03*
X232250Y291385D02*
D03*
X264500Y375775D02*
D03*
X375750Y322588D02*
D03*
X145319Y249000D02*
D03*
X160000Y186500D02*
D03*
X84365Y251500D02*
D03*
X22702Y246500D02*
D03*
X52108Y254060D02*
D03*
X102727Y162527D02*
D03*
X66500D02*
D03*
X77704D02*
D03*
X115250D02*
D03*
X142000Y178086D02*
D03*
X130429Y181250D02*
D03*
X114250Y104000D02*
D03*
X72036Y102261D02*
D03*
X41916Y93504D02*
D03*
X55090Y106500D02*
D03*
X91005Y119250D02*
D03*
X129500Y106500D02*
D03*
X403000Y185091D02*
D03*
X403000Y274431D02*
D03*
D81*
X55400Y226115D02*
G03*
X54105Y227410I-1295J0D01*
G01*
Y219640D02*
G03*
X55400Y220935I0J1295D01*
G01*
Y220935D02*
G03*
X54105Y222230I-1295J0D01*
G01*
X55095Y231295D02*
G03*
X53800Y232590I-1295J0D01*
G01*
Y230000D02*
G03*
X55095Y231295I0J1295D01*
G01*
X52500Y233885D02*
G03*
X53795Y232590I1295J0D01*
G01*
X52500Y228705D02*
G03*
X53795Y227410I1295J0D01*
G01*
Y230000D02*
G03*
X52500Y228705I0J-1295D01*
G01*
X54105Y224820D02*
G03*
X55400Y226115I0J1295D01*
G01*
X53795Y219640D02*
G03*
X52500Y218345I0J-1295D01*
G01*
Y223525D02*
G03*
X53795Y222230I1295J0D01*
G01*
Y224820D02*
G03*
X52500Y223525I0J-1295D01*
G01*
X107738Y304512D02*
X112400Y299850D01*
X92777Y300665D02*
X96625Y304512D01*
X107550Y307528D02*
X112573Y312550D01*
X89737Y301889D02*
X95376Y307528D01*
X95393D02*
X95393Y307528D01*
X96625Y304512D02*
X96642D01*
X96642Y304512D01*
X95376Y307528D02*
X95393D01*
X95393Y307528D02*
X107550D01*
X96642Y304512D02*
X107738D01*
X89737Y278228D02*
Y301889D01*
X87032Y275523D02*
X89737Y278228D01*
X88292Y272483D02*
X92777Y276968D01*
Y300665D01*
X87032Y272477D02*
X87038Y272483D01*
X88292D01*
X72477Y275523D02*
X87032D01*
X72477Y272477D02*
X87032D01*
X71500Y271500D02*
X72477Y272477D01*
X71500Y276500D02*
X72477Y275523D01*
X94863Y223391D02*
X96140D01*
X81860Y220250D02*
X95400D01*
X112700Y227950D02*
X117500D01*
X96140Y223391D02*
X99000Y226250D01*
X102300Y222950D01*
X107700D02*
X112700Y227950D01*
X102300Y222950D02*
X107700D01*
X70517Y242483D02*
X71500Y241500D01*
X57032Y242483D02*
X70517D01*
X55095Y231295D02*
Y231295D01*
X55400Y226115D02*
Y226115D01*
X75183Y208750D02*
X77250Y210818D01*
X55400Y220935D02*
Y220935D01*
X77250Y210818D02*
Y219939D01*
X56304Y208750D02*
X75183D01*
X53795Y232590D02*
X53800D01*
X52500Y237951D02*
X57032Y242483D01*
X53795Y227410D02*
X54105D01*
X53795Y230000D02*
X53800D01*
X52500Y233885D02*
Y236129D01*
Y237951D01*
Y228705D02*
Y228705D01*
X53795Y222230D02*
X54105D01*
X53795Y224820D02*
X54105D01*
X53795Y219640D02*
X54105D01*
X52500Y212554D02*
X56304Y208750D01*
X52500Y223525D02*
Y223525D01*
Y212554D02*
Y215250D01*
Y218345D01*
X95400Y220250D02*
X99000Y216650D01*
X102188Y219838D02*
X108156D01*
X112744Y215250D01*
X117500D01*
X99000Y216650D02*
X102188Y219838D01*
X70523Y245523D02*
X71500Y246500D01*
X80290Y218680D02*
X81860Y220250D01*
X49460Y239210D02*
X55773Y245523D01*
X70523D01*
X80290Y209558D02*
Y218680D01*
X76442Y205710D02*
X80290Y209558D01*
X55045Y205710D02*
X76442D01*
X49460Y211295D02*
Y239210D01*
Y211295D02*
X55045Y205710D01*
X94762Y223290D02*
X94863Y223391D01*
X80601Y223290D02*
X94762D01*
X77250Y219939D02*
X80601Y223290D01*
X112400Y299850D02*
X117250D01*
X112573Y312550D02*
X117250D01*
D82*
X64618Y390689D02*
D03*
X122618D02*
D03*
Y377689D02*
D03*
X64618Y371189D02*
D03*
Y377689D02*
D03*
Y384189D02*
D03*
X122618D02*
D03*
Y371189D02*
D03*
D83*
X171500Y215250D02*
D03*
Y240650D02*
D03*
X117500D02*
D03*
Y227950D02*
D03*
Y215250D02*
D03*
X171500Y227950D02*
D03*
Y253350D02*
D03*
X117500D02*
D03*
X171250Y274450D02*
D03*
X117250D02*
D03*
Y299850D02*
D03*
X171250Y312550D02*
D03*
Y299850D02*
D03*
Y287150D02*
D03*
X117250D02*
D03*
Y312550D02*
D03*
D84*
X276914Y360775D02*
D03*
Y365775D02*
D03*
Y370775D02*
D03*
Y375775D02*
D03*
X305914Y370775D02*
D03*
Y375775D02*
D03*
Y365775D02*
D03*
Y360775D02*
D03*
D85*
X291414Y368275D02*
D03*
D86*
X71500Y266500D02*
D03*
Y261500D02*
D03*
Y256500D02*
D03*
Y251500D02*
D03*
Y231500D02*
D03*
Y236500D02*
D03*
Y241500D02*
D03*
Y246500D02*
D03*
Y276500D02*
D03*
Y271500D02*
D03*
X36500D02*
D03*
Y276500D02*
D03*
Y246500D02*
D03*
Y241500D02*
D03*
Y236500D02*
D03*
Y231500D02*
D03*
Y251500D02*
D03*
Y256500D02*
D03*
Y261500D02*
D03*
Y266500D02*
D03*
D87*
X279500Y339500D02*
D03*
X264500D02*
D03*
X122500Y343710D02*
D03*
X107500D02*
D03*
D88*
X421000Y193594D02*
D03*
X412500D02*
D03*
X279005Y198941D02*
D03*
X270505D02*
D03*
X224129Y199191D02*
D03*
X232629D02*
D03*
X27250Y357460D02*
D03*
X35750D02*
D03*
X27250Y367710D02*
D03*
X35750D02*
D03*
X27285Y397960D02*
D03*
X35785D02*
D03*
X35750Y347460D02*
D03*
X27250D02*
D03*
X35750Y377710D02*
D03*
X27250D02*
D03*
X35750Y387710D02*
D03*
X27250D02*
D03*
X334750Y343750D02*
D03*
X326250D02*
D03*
X334750Y354236D02*
D03*
X326250D02*
D03*
Y334250D02*
D03*
X334750D02*
D03*
X326000Y363750D02*
D03*
X334500D02*
D03*
X394750Y274431D02*
D03*
X386250D02*
D03*
D89*
X95000Y71000D02*
D03*
X406000Y41000D02*
D03*
X413000Y452000D02*
D03*
X95000Y437000D02*
D03*
D90*
X243755Y190711D02*
D03*
Y199211D02*
D03*
X258755Y190441D02*
D03*
Y198941D02*
D03*
X338500Y382750D02*
D03*
Y374250D02*
D03*
X327500Y374500D02*
D03*
Y383000D02*
D03*
X394750Y284000D02*
D03*
Y292500D02*
D03*
X403000Y202094D02*
D03*
Y193594D02*
D03*
D91*
X71500Y251500D02*
X84365D01*
X22702Y246500D02*
X36500D01*
M02*
